FILE_TYPE = MACRO_DRAWING;
SET COLOR_WIRE YELLOW;
SET COLOR_PROP MONO;
SET COLOR_DOT WHITE;
SET COLOR_ARC YELLOW;
SET COLOR_BODY GREEN;
SET COLOR_NOTE MONO;
SET PROP_DISPLAY VALUE;
SET PAGE_NUMBER P231;
FORCEADD CAP..1
(-7925 1000);
FORCEPROP 0 LAST GROUP PWR_MLCC_CAP
J 0
(-7869 737);
DISPLAY 0.638298 (-7869 737);
PAINT BROWN (-7869 737);
DISPLAY BOTH (-7869 737);
FORCEPROP 1 LAST PART_NUMBER E15431-001
J 0
(-7875 850);
DISPLAY 0.617021 (-7875 850);
PAINT BLUE (-7875 850);
FORCEPROP 1 LAST MATERIAL X6S
J 0
(-7875 900);
DISPLAY 0.617021 (-7875 900);
PAINT SKYBLUE (-7875 900);
FORCEPROP 1 LASTPIN (-7925 1100) $PN 1
J 0
(-7915 1080);
DISPLAY 0.617021 (-7915 1080);
PAINT GREEN (-7915 1080);
FORCEPROP 1 LASTPIN (-7925 900) $PN 2
J 0
(-7915 880);
DISPLAY 0.617021 (-7915 880);
PAINT GREEN (-7915 880);
FORCEPROP 1 LAST VALUE 10UF
J 0
(-7875 1050);
DISPLAY 0.617021 (-7875 1050);
PAINT SKYBLUE (-7875 1050);
FORCEPROP 1 LAST LOCATION C6F6
J 0
(-7875 1100);
DISPLAY 0.617021 (-7875 1100);
PAINT AQUA (-7875 1100);
FORCEPROP 1 LAST VOLTAGE 4V
J 0
(-7875 1000);
DISPLAY 0.638298 (-7875 1000);
PAINT SKYBLUE (-7875 1000);
FORCEPROP 1 LAST TOLERANCE 20%
J 0
(-7875 950);
DISPLAY 0.617021 (-7875 950);
PAINT SKYBLUE (-7875 950);
FORCEPROP 1 LAST PACK_TYPE 0603LF
J 0
(-7875 800);
DISPLAY 0.617021 (-7875 800);
PAINT SKYBLUE (-7875 800);
FORCEPROP 2 LAST CDS_LIB mstr_discrete
J 0
(-7925 1000);
PAINT ORANGE (-7925 1000);
DISPLAY INVISIBLE (-7925 1000);
FORCEPROP 2 LAST CDS_LOCATION C6F6
J 0
(-7875 1100);
DISPLAY 0.617021 (-7875 1100);
PAINT AQUA (-7875 1100);
DISPLAY INVISIBLE (-7875 1100);
FORCEPROP 2 LAST CDS_SEC 1
J 0
(-7875 1200);
PAINT MONO (-7875 1200);
DISPLAY INVISIBLE (-7875 1200);
FORCEPROP 2 LAST $SEC 1
J 0
(-7875 1200);
PAINT MONO (-7875 1200);
DISPLAY INVISIBLE (-7875 1200);
FORCEPROP 2 LAST BOM_COST MEM_VRD_PVPP_AB
J 0
(-7875 1150);
PAINT MONO (-7875 1150);
DISPLAY INVISIBLE (-7875 1150);
FORCEPROP 1 LAST PATH I122
J 0
(-7875 1150);
DISPLAY 0.978723 (-7875 1150);
PAINT WHITE (-7875 1150);
DISPLAY INVISIBLE (-7875 1150);
FORCEPROP 2 LAST ROOM PVPP_KLM_VR
J 0
(-7875 1150);
PAINT MONO (-7875 1150);
DISPLAY INVISIBLE (-7875 1150);
FORCEADD PVPP_ABC..1
(-7925 1250);
FORCEPROP 3 LASTPIN (-7925 1200) SIG_NAME PVPP_ABC\g
J 0
(-7915 1210);
DISPLAY 0.659574 (-7915 1210);
PAINT MONO (-7915 1210);
DISPLAY INVISIBLE (-7915 1210);
FORCEPROP 1 LAST HDL_POWER PVPP_ABC
J 1
(-7925 1300);
DISPLAY 0.872340 (-7925 1300);
PAINT GREEN (-7925 1300);
DISPLAY INVISIBLE (-7925 1300);
FORCEPROP 1 LAST BODY_TYPE PLUMBING
J 0
(-7970 1207);
DISPLAY 0.340426 (-7970 1207);
PAINT GREEN (-7970 1207);
DISPLAY INVISIBLE (-7970 1207);
FORCEPROP 2 LAST ROOM PVPP_KLM_VR
J 0
(-7675 1350);
PAINT ORANGE (-7675 1350);
DISPLAY INVISIBLE (-7675 1350);
FORCEPROP 1 LAST PATH I123
J 0
(-7875 1275);
DISPLAY 0.872340 (-7875 1275);
PAINT AQUA (-7875 1275);
DISPLAY INVISIBLE (-7875 1275);
FORCEPROP 2 LAST BOM_COST MEM_VRD_PVPP_AB
J 0
(-7850 1350);
PAINT MONO (-7850 1350);
DISPLAY INVISIBLE (-7850 1350);
FORCEPROP 2 LAST CDS_LIB mstr_symbols
J 0
(-7925 1250);
PAINT ORANGE (-7925 1250);
DISPLAY INVISIBLE (-7925 1250);
FORCEPROP 1 LAST VOLTAGE 2.5V
J 0
(-7970 1207);
DISPLAY 0.340426 (-7970 1207);
PAINT SKYBLUE (-7970 1207);
DISPLAY INVISIBLE (-7970 1207);
FORCEADD CAP..1
(-7625 1000);
FORCEPROP 0 LAST GROUP PWR_MLCC_CAP
J 0
(-7569 687);
DISPLAY 0.638298 (-7569 687);
PAINT BROWN (-7569 687);
DISPLAY BOTH (-7569 687);
FORCEPROP 1 LAST PART_NUMBER E15431-001
J 0
(-7575 850);
DISPLAY 0.617021 (-7575 850);
PAINT BLUE (-7575 850);
FORCEPROP 1 LAST VOLTAGE 4V
J 0
(-7575 1000);
DISPLAY 0.638298 (-7575 1000);
PAINT SKYBLUE (-7575 1000);
FORCEPROP 1 LASTPIN (-7625 1100) $PN 1
J 0
(-7615 1080);
DISPLAY 0.617021 (-7615 1080);
PAINT GREEN (-7615 1080);
FORCEPROP 1 LAST LOCATION C4T6
J 0
(-7575 1100);
DISPLAY 0.617021 (-7575 1100);
PAINT AQUA (-7575 1100);
FORCEPROP 1 LAST VALUE 10UF
J 0
(-7575 1050);
DISPLAY 0.617021 (-7575 1050);
PAINT SKYBLUE (-7575 1050);
FORCEPROP 1 LAST TOLERANCE 20%
J 0
(-7575 950);
DISPLAY 0.617021 (-7575 950);
PAINT SKYBLUE (-7575 950);
FORCEPROP 1 LAST MATERIAL X6S
J 0
(-7575 900);
DISPLAY 0.617021 (-7575 900);
PAINT SKYBLUE (-7575 900);
FORCEPROP 1 LASTPIN (-7625 900) $PN 2
J 0
(-7615 880);
DISPLAY 0.617021 (-7615 880);
PAINT GREEN (-7615 880);
FORCEPROP 1 LAST PACK_TYPE 0603LF
J 0
(-7575 800);
DISPLAY 0.617021 (-7575 800);
PAINT SKYBLUE (-7575 800);
FORCEPROP 2 LAST CDS_LIB mstr_discrete
J 0
(-7625 1000);
PAINT ORANGE (-7625 1000);
DISPLAY INVISIBLE (-7625 1000);
FORCEPROP 2 LAST ROOM PVPP_KLM_VR
J 0
(-7575 1150);
PAINT MONO (-7575 1150);
DISPLAY INVISIBLE (-7575 1150);
FORCEPROP 1 LAST PATH I124
J 0
(-7575 1150);
DISPLAY 0.978723 (-7575 1150);
PAINT WHITE (-7575 1150);
DISPLAY INVISIBLE (-7575 1150);
FORCEPROP 2 LAST CDS_LOCATION C4T6
J 0
(-7575 1100);
DISPLAY 0.617021 (-7575 1100);
PAINT AQUA (-7575 1100);
DISPLAY INVISIBLE (-7575 1100);
FORCEPROP 2 LAST $SEC 1
J 0
(-7575 1200);
PAINT MONO (-7575 1200);
DISPLAY INVISIBLE (-7575 1200);
FORCEPROP 2 LAST CDS_SEC 1
J 0
(-7575 1200);
PAINT MONO (-7575 1200);
DISPLAY INVISIBLE (-7575 1200);
FORCEPROP 2 LAST BOM_COST MEM_VRD_PVPP_AB
J 0
(-7575 1150);
PAINT MONO (-7575 1150);
DISPLAY INVISIBLE (-7575 1150);
FORCEADD CAP..1
(-7350 1000);
FORCEPROP 0 LAST GROUP PWR_MLCC_CAP
J 0
(-7294 737);
DISPLAY 0.638298 (-7294 737);
PAINT BROWN (-7294 737);
DISPLAY BOTH (-7294 737);
FORCEPROP 1 LAST PART_NUMBER E15431-001
J 0
(-7300 850);
DISPLAY 0.617021 (-7300 850);
PAINT BLUE (-7300 850);
FORCEPROP 1 LAST VOLTAGE 4V
J 0
(-7300 1000);
DISPLAY 0.638298 (-7300 1000);
PAINT SKYBLUE (-7300 1000);
FORCEPROP 1 LAST PACK_TYPE 0603LF
J 0
(-7300 800);
DISPLAY 0.617021 (-7300 800);
PAINT SKYBLUE (-7300 800);
FORCEPROP 1 LAST LOCATION C4T5
J 0
(-7300 1100);
DISPLAY 0.617021 (-7300 1100);
PAINT AQUA (-7300 1100);
FORCEPROP 1 LAST VALUE 10UF
J 0
(-7300 1050);
DISPLAY 0.617021 (-7300 1050);
PAINT SKYBLUE (-7300 1050);
FORCEPROP 1 LASTPIN (-7350 1100) $PN 1
J 0
(-7340 1080);
DISPLAY 0.617021 (-7340 1080);
PAINT GREEN (-7340 1080);
FORCEPROP 1 LASTPIN (-7350 900) $PN 2
J 0
(-7340 880);
DISPLAY 0.617021 (-7340 880);
PAINT GREEN (-7340 880);
FORCEPROP 1 LAST TOLERANCE 20%
J 0
(-7300 950);
DISPLAY 0.617021 (-7300 950);
PAINT SKYBLUE (-7300 950);
FORCEPROP 1 LAST MATERIAL X6S
J 0
(-7300 900);
DISPLAY 0.617021 (-7300 900);
PAINT SKYBLUE (-7300 900);
FORCEPROP 2 LAST BOM_COST MEM_VRD_PVPP_AB
J 0
(-7300 1150);
PAINT MONO (-7300 1150);
DISPLAY INVISIBLE (-7300 1150);
FORCEPROP 2 LAST $SEC 1
J 0
(-7300 1200);
PAINT MONO (-7300 1200);
DISPLAY INVISIBLE (-7300 1200);
FORCEPROP 2 LAST CDS_SEC 1
J 0
(-7300 1200);
PAINT MONO (-7300 1200);
DISPLAY INVISIBLE (-7300 1200);
FORCEPROP 1 LAST PATH I125
J 0
(-7300 1150);
DISPLAY 0.978723 (-7300 1150);
PAINT WHITE (-7300 1150);
DISPLAY INVISIBLE (-7300 1150);
FORCEPROP 2 LAST ROOM PVPP_KLM_VR
J 0
(-7300 1150);
PAINT MONO (-7300 1150);
DISPLAY INVISIBLE (-7300 1150);
FORCEPROP 2 LAST CDS_LOCATION C4T5
J 0
(-7300 1100);
DISPLAY 0.617021 (-7300 1100);
PAINT AQUA (-7300 1100);
DISPLAY INVISIBLE (-7300 1100);
FORCEPROP 2 LAST CDS_LIB mstr_discrete
J 0
(-7350 1000);
PAINT ORANGE (-7350 1000);
DISPLAY INVISIBLE (-7350 1000);
FORCEADD CAP..1
(-7075 975);
FORCEPROP 0 LAST GROUP PWR_MLCC_CAP
J 0
(-7019 687);
DISPLAY 0.638298 (-7019 687);
PAINT BROWN (-7019 687);
DISPLAY BOTH (-7019 687);
FORCEPROP 1 LAST LOCATION C6G1
J 0
(-7025 1075);
DISPLAY 0.617021 (-7025 1075);
PAINT AQUA (-7025 1075);
FORCEPROP 1 LAST VALUE 10UF
J 0
(-7025 1025);
DISPLAY 0.617021 (-7025 1025);
PAINT SKYBLUE (-7025 1025);
FORCEPROP 1 LAST TOLERANCE 20%
J 0
(-7025 925);
DISPLAY 0.617021 (-7025 925);
PAINT SKYBLUE (-7025 925);
FORCEPROP 1 LAST MATERIAL X6S
J 0
(-7025 875);
DISPLAY 0.617021 (-7025 875);
PAINT SKYBLUE (-7025 875);
FORCEPROP 1 LAST PART_NUMBER E15431-001
J 0
(-7025 825);
DISPLAY 0.617021 (-7025 825);
PAINT BLUE (-7025 825);
FORCEPROP 1 LAST PACK_TYPE 0603LF
J 0
(-7025 775);
DISPLAY 0.617021 (-7025 775);
PAINT SKYBLUE (-7025 775);
FORCEPROP 1 LAST VOLTAGE 4V
J 0
(-7025 975);
DISPLAY 0.638298 (-7025 975);
PAINT SKYBLUE (-7025 975);
FORCEPROP 1 LASTPIN (-7075 875) $PN 2
J 0
(-7065 855);
DISPLAY 0.617021 (-7065 855);
PAINT GREEN (-7065 855);
FORCEPROP 1 LASTPIN (-7075 1075) $PN 1
J 0
(-7065 1055);
DISPLAY 0.617021 (-7065 1055);
PAINT GREEN (-7065 1055);
FORCEPROP 2 LAST BOM_COST MEM_VRD_PVPP_AB
J 0
(-7025 1125);
PAINT MONO (-7025 1125);
DISPLAY INVISIBLE (-7025 1125);
FORCEPROP 2 LAST CDS_SEC 1
J 0
(-7025 1175);
PAINT MONO (-7025 1175);
DISPLAY INVISIBLE (-7025 1175);
FORCEPROP 2 LAST $SEC 1
J 0
(-7025 1175);
PAINT MONO (-7025 1175);
DISPLAY INVISIBLE (-7025 1175);
FORCEPROP 2 LAST CDS_LOCATION C6G1
J 0
(-7025 1075);
DISPLAY 0.617021 (-7025 1075);
PAINT AQUA (-7025 1075);
DISPLAY INVISIBLE (-7025 1075);
FORCEPROP 1 LAST PATH I126
J 0
(-7025 1125);
DISPLAY 0.978723 (-7025 1125);
PAINT WHITE (-7025 1125);
DISPLAY INVISIBLE (-7025 1125);
FORCEPROP 2 LAST ROOM PVPP_KLM_VR
J 0
(-7025 1125);
PAINT MONO (-7025 1125);
DISPLAY INVISIBLE (-7025 1125);
FORCEPROP 2 LAST CDS_LIB mstr_discrete
J 0
(-7075 975);
PAINT ORANGE (-7075 975);
DISPLAY INVISIBLE (-7075 975);
FORCEADD GND..1
(-6625 2200);
FORCEPROP 3 LASTPIN (-6625 2250) SIG_NAME GND\g
J 0
(-6615 2260);
DISPLAY 0.659574 (-6615 2260);
PAINT MONO (-6615 2260);
DISPLAY INVISIBLE (-6615 2260);
FORCEPROP 1 LAST HDL_POWER GND
J 0
(-6625 2350);
DISPLAY 0.680851 (-6625 2350);
PAINT GREEN (-6625 2350);
DISPLAY INVISIBLE (-6625 2350);
FORCEPROP 1 LAST BODY_TYPE PLUMBING
J 0
(-6670 2157);
DISPLAY 0.340426 (-6670 2157);
PAINT GREEN (-6670 2157);
DISPLAY INVISIBLE (-6670 2157);
FORCEPROP 1 LAST VOLTAGE 0
J 0
(-6625 2200);
PAINT SKYBLUE (-6625 2200);
DISPLAY INVISIBLE (-6625 2200);
FORCEPROP 1 LAST SIZE 1B
J 0
(-6550 2150);
DISPLAY 0.680851 (-6550 2150);
PAINT ORANGE (-6550 2150);
DISPLAY INVISIBLE (-6550 2150);
FORCEPROP 2 LAST CDS_LIB mstr_symbols
J 0
(-6625 2200);
PAINT MONO (-6625 2200);
DISPLAY INVISIBLE (-6625 2200);
FORCEPROP 1 LAST PATH I127
J 0
(-6550 2200);
DISPLAY 0.872340 (-6550 2200);
PAINT AQUA (-6550 2200);
DISPLAY INVISIBLE (-6550 2200);
FORCEPROP 2 LAST BOM_COST PVPP_KLM_VR
J 0
(-7375 2325);
DISPLAY 1.042553 (-7375 2325);
PAINT WHITE (-7375 2325);
DISPLAY INVISIBLE (-7375 2325);
FORCEPROP 2 LAST BOM SYSB_CPLD
J 0
(-7375 2375);
DISPLAY 1.042553 (-7375 2375);
PAINT ORANGE (-7375 2375);
DISPLAY INVISIBLE (-7375 2375);
FORCEPROP 2 LAST ROOM PVPP_KLM_VR
J 0
(-7375 2275);
DISPLAY 1.042553 (-7375 2275);
PAINT GREEN (-7375 2275);
DISPLAY INVISIBLE (-7375 2275);
FORCEADD CAP..1
(-6800 1000);
FORCEPROP 0 LAST GROUP PWR_MLCC_CAP
J 0
(-6744 737);
DISPLAY 0.638298 (-6744 737);
PAINT BROWN (-6744 737);
DISPLAY BOTH (-6744 737);
FORCEPROP 1 LAST TOLERANCE 20%
J 0
(-6750 950);
DISPLAY 0.617021 (-6750 950);
PAINT SKYBLUE (-6750 950);
FORCEPROP 1 LAST VOLTAGE 4V
J 0
(-6750 1000);
DISPLAY 0.638298 (-6750 1000);
PAINT SKYBLUE (-6750 1000);
FORCEPROP 1 LAST LOCATION C6G2
J 0
(-6750 1100);
DISPLAY 0.617021 (-6750 1100);
PAINT AQUA (-6750 1100);
FORCEPROP 1 LAST PACK_TYPE 0603LF
J 0
(-6750 800);
DISPLAY 0.617021 (-6750 800);
PAINT SKYBLUE (-6750 800);
FORCEPROP 1 LASTPIN (-6800 900) $PN 2
J 0
(-6790 880);
DISPLAY 0.617021 (-6790 880);
PAINT GREEN (-6790 880);
FORCEPROP 1 LAST VALUE 10UF
J 0
(-6750 1050);
DISPLAY 0.617021 (-6750 1050);
PAINT SKYBLUE (-6750 1050);
FORCEPROP 1 LASTPIN (-6800 1100) $PN 1
J 0
(-6790 1080);
DISPLAY 0.617021 (-6790 1080);
PAINT GREEN (-6790 1080);
FORCEPROP 1 LAST PART_NUMBER E15431-001
J 0
(-6750 850);
DISPLAY 0.617021 (-6750 850);
PAINT BLUE (-6750 850);
FORCEPROP 1 LAST MATERIAL X6S
J 0
(-6750 900);
DISPLAY 0.617021 (-6750 900);
PAINT SKYBLUE (-6750 900);
FORCEPROP 2 LAST BOM_COST MEM_VRD_PVPP_AB
J 0
(-6750 1150);
PAINT MONO (-6750 1150);
DISPLAY INVISIBLE (-6750 1150);
FORCEPROP 2 LAST CDS_SEC 1
J 0
(-6750 1200);
PAINT MONO (-6750 1200);
DISPLAY INVISIBLE (-6750 1200);
FORCEPROP 2 LAST $SEC 1
J 0
(-6750 1200);
PAINT MONO (-6750 1200);
DISPLAY INVISIBLE (-6750 1200);
FORCEPROP 2 LAST CDS_LOCATION C6G2
J 0
(-6750 1100);
DISPLAY 0.617021 (-6750 1100);
PAINT AQUA (-6750 1100);
DISPLAY INVISIBLE (-6750 1100);
FORCEPROP 1 LAST PATH I128
J 0
(-6750 1150);
DISPLAY 0.978723 (-6750 1150);
PAINT WHITE (-6750 1150);
DISPLAY INVISIBLE (-6750 1150);
FORCEPROP 2 LAST ROOM PVPP_KLM_VR
J 0
(-6750 1150);
PAINT MONO (-6750 1150);
DISPLAY INVISIBLE (-6750 1150);
FORCEPROP 2 LAST CDS_LIB mstr_discrete
J 0
(-6800 1000);
PAINT ORANGE (-6800 1000);
DISPLAY INVISIBLE (-6800 1000);
FORCEADD CAP..1
(-6500 1000);
FORCEPROP 0 LAST GROUP PWR_MLCC_CAP
J 0
(-6444 687);
DISPLAY 0.638298 (-6444 687);
PAINT BROWN (-6444 687);
DISPLAY BOTH (-6444 687);
FORCEPROP 1 LAST PACK_TYPE 0603LF
J 0
(-6450 800);
DISPLAY 0.617021 (-6450 800);
PAINT SKYBLUE (-6450 800);
FORCEPROP 1 LAST VALUE 10UF
J 0
(-6450 1050);
DISPLAY 0.617021 (-6450 1050);
PAINT SKYBLUE (-6450 1050);
FORCEPROP 1 LASTPIN (-6500 900) $PN 2
J 0
(-6490 880);
DISPLAY 0.617021 (-6490 880);
PAINT GREEN (-6490 880);
FORCEPROP 1 LAST LOCATION C4U2
J 0
(-6450 1100);
DISPLAY 0.617021 (-6450 1100);
PAINT AQUA (-6450 1100);
FORCEPROP 1 LASTPIN (-6500 1100) $PN 1
J 0
(-6490 1080);
DISPLAY 0.617021 (-6490 1080);
PAINT GREEN (-6490 1080);
FORCEPROP 1 LAST PART_NUMBER E15431-001
J 0
(-6450 850);
DISPLAY 0.617021 (-6450 850);
PAINT BLUE (-6450 850);
FORCEPROP 1 LAST MATERIAL X6S
J 0
(-6450 900);
DISPLAY 0.617021 (-6450 900);
PAINT SKYBLUE (-6450 900);
FORCEPROP 1 LAST VOLTAGE 4V
J 0
(-6450 1000);
DISPLAY 0.638298 (-6450 1000);
PAINT SKYBLUE (-6450 1000);
FORCEPROP 1 LAST TOLERANCE 20%
J 0
(-6450 950);
DISPLAY 0.617021 (-6450 950);
PAINT SKYBLUE (-6450 950);
FORCEPROP 2 LAST $SEC 1
J 0
(-6450 1200);
PAINT MONO (-6450 1200);
DISPLAY INVISIBLE (-6450 1200);
FORCEPROP 2 LAST CDS_SEC 1
J 0
(-6450 1200);
PAINT MONO (-6450 1200);
DISPLAY INVISIBLE (-6450 1200);
FORCEPROP 2 LAST ROOM PVPP_KLM_VR
J 0
(-6450 1150);
PAINT MONO (-6450 1150);
DISPLAY INVISIBLE (-6450 1150);
FORCEPROP 1 LAST PATH I129
J 0
(-6450 1150);
DISPLAY 0.978723 (-6450 1150);
PAINT WHITE (-6450 1150);
DISPLAY INVISIBLE (-6450 1150);
FORCEPROP 2 LAST BOM_COST MEM_VRD_PVPP_AB
J 0
(-6450 1150);
PAINT MONO (-6450 1150);
DISPLAY INVISIBLE (-6450 1150);
FORCEPROP 2 LAST CDS_LOCATION C4U2
J 0
(-6450 1100);
DISPLAY 0.617021 (-6450 1100);
PAINT AQUA (-6450 1100);
DISPLAY INVISIBLE (-6450 1100);
FORCEPROP 2 LAST CDS_LIB mstr_discrete
J 0
(-6500 1000);
PAINT ORANGE (-6500 1000);
DISPLAY INVISIBLE (-6500 1000);
FORCEADD CAP..1
(-6225 1000);
FORCEPROP 1 LAST PART_NUMBER E15431-001
J 0
(-6175 850);
DISPLAY 0.617021 (-6175 850);
PAINT BLUE (-6175 850);
FORCEPROP 0 LAST GROUP PWR_MLCC_CAP
J 0
(-6169 737);
DISPLAY 0.638298 (-6169 737);
PAINT BROWN (-6169 737);
DISPLAY BOTH (-6169 737);
FORCEPROP 1 LAST VOLTAGE 4V
J 0
(-6175 1000);
DISPLAY 0.638298 (-6175 1000);
PAINT SKYBLUE (-6175 1000);
FORCEPROP 1 LASTPIN (-6225 900) $PN 2
J 0
(-6215 880);
DISPLAY 0.617021 (-6215 880);
PAINT GREEN (-6215 880);
FORCEPROP 1 LAST PACK_TYPE 0603LF
J 0
(-6175 800);
DISPLAY 0.617021 (-6175 800);
PAINT SKYBLUE (-6175 800);
FORCEPROP 1 LAST VALUE 10UF
J 0
(-6175 1050);
DISPLAY 0.617021 (-6175 1050);
PAINT SKYBLUE (-6175 1050);
FORCEPROP 1 LASTPIN (-6225 1100) $PN 1
J 0
(-6215 1080);
DISPLAY 0.617021 (-6215 1080);
PAINT GREEN (-6215 1080);
FORCEPROP 1 LAST MATERIAL X6S
J 0
(-6175 900);
DISPLAY 0.617021 (-6175 900);
PAINT SKYBLUE (-6175 900);
FORCEPROP 1 LAST LOCATION C4U1
J 0
(-6175 1100);
DISPLAY 0.617021 (-6175 1100);
PAINT AQUA (-6175 1100);
FORCEPROP 1 LAST TOLERANCE 20%
J 0
(-6175 950);
DISPLAY 0.617021 (-6175 950);
PAINT SKYBLUE (-6175 950);
FORCEPROP 2 LAST $SEC 1
J 0
(-6175 1200);
PAINT MONO (-6175 1200);
DISPLAY INVISIBLE (-6175 1200);
FORCEPROP 2 LAST CDS_SEC 1
J 0
(-6175 1200);
PAINT MONO (-6175 1200);
DISPLAY INVISIBLE (-6175 1200);
FORCEPROP 2 LAST ROOM PVPP_KLM_VR
J 0
(-6175 1150);
PAINT MONO (-6175 1150);
DISPLAY INVISIBLE (-6175 1150);
FORCEPROP 2 LAST BOM_COST MEM_VRD_PVPP_AB
J 0
(-6175 1150);
PAINT MONO (-6175 1150);
DISPLAY INVISIBLE (-6175 1150);
FORCEPROP 1 LAST PATH I130
J 0
(-6175 1150);
DISPLAY 0.978723 (-6175 1150);
PAINT WHITE (-6175 1150);
DISPLAY INVISIBLE (-6175 1150);
FORCEPROP 2 LAST CDS_LOCATION C4U1
J 0
(-6175 1100);
DISPLAY 0.617021 (-6175 1100);
PAINT AQUA (-6175 1100);
DISPLAY INVISIBLE (-6175 1100);
FORCEPROP 2 LAST CDS_LIB mstr_discrete
J 0
(-6225 1000);
PAINT MONO (-6225 1000);
DISPLAY INVISIBLE (-6225 1000);
FORCEADD CAP..1
(-5925 1000);
FORCEPROP 0 LAST GROUP PWR_MLCC_CAP
J 0
(-5869 687);
DISPLAY 0.638298 (-5869 687);
PAINT BROWN (-5869 687);
DISPLAY BOTH (-5869 687);
FORCEPROP 1 LAST MATERIAL X6S
J 0
(-5875 900);
DISPLAY 0.617021 (-5875 900);
PAINT SKYBLUE (-5875 900);
FORCEPROP 1 LAST PART_NUMBER E15431-001
J 0
(-5875 850);
DISPLAY 0.617021 (-5875 850);
PAINT BLUE (-5875 850);
FORCEPROP 1 LAST PACK_TYPE 0603LF
J 0
(-5875 800);
DISPLAY 0.617021 (-5875 800);
PAINT SKYBLUE (-5875 800);
FORCEPROP 1 LAST LOCATION C6G4
J 0
(-5875 1100);
DISPLAY 0.617021 (-5875 1100);
PAINT AQUA (-5875 1100);
FORCEPROP 1 LASTPIN (-5925 1100) $PN 1
J 0
(-5915 1080);
DISPLAY 0.617021 (-5915 1080);
PAINT GREEN (-5915 1080);
FORCEPROP 1 LASTPIN (-5925 900) $PN 2
J 0
(-5915 880);
DISPLAY 0.617021 (-5915 880);
PAINT GREEN (-5915 880);
FORCEPROP 1 LAST VOLTAGE 4V
J 0
(-5875 1000);
DISPLAY 0.638298 (-5875 1000);
PAINT SKYBLUE (-5875 1000);
FORCEPROP 1 LAST VALUE 10UF
J 0
(-5875 1050);
DISPLAY 0.617021 (-5875 1050);
PAINT SKYBLUE (-5875 1050);
FORCEPROP 1 LAST TOLERANCE 20%
J 0
(-5875 950);
DISPLAY 0.617021 (-5875 950);
PAINT SKYBLUE (-5875 950);
FORCEPROP 2 LAST BOM_COST MEM_VRD_PVPP_AB
J 0
(-5875 1150);
PAINT MONO (-5875 1150);
DISPLAY INVISIBLE (-5875 1150);
FORCEPROP 2 LAST CDS_SEC 1
J 0
(-5875 1200);
PAINT MONO (-5875 1200);
DISPLAY INVISIBLE (-5875 1200);
FORCEPROP 2 LAST $SEC 1
J 0
(-5875 1200);
PAINT MONO (-5875 1200);
DISPLAY INVISIBLE (-5875 1200);
FORCEPROP 2 LAST CDS_LOCATION C6G4
J 0
(-5875 1100);
DISPLAY 0.617021 (-5875 1100);
PAINT AQUA (-5875 1100);
DISPLAY INVISIBLE (-5875 1100);
FORCEPROP 1 LAST PATH I131
J 0
(-5875 1150);
DISPLAY 0.978723 (-5875 1150);
PAINT WHITE (-5875 1150);
DISPLAY INVISIBLE (-5875 1150);
FORCEPROP 2 LAST ROOM PVPP_KLM_VR
J 0
(-5875 1150);
PAINT MONO (-5875 1150);
DISPLAY INVISIBLE (-5875 1150);
FORCEPROP 2 LAST CDS_LIB mstr_discrete
J 0
(-5925 1000);
PAINT MONO (-5925 1000);
DISPLAY INVISIBLE (-5925 1000);
FORCEADD AGND_SCSI..1
(-6175 2325);
FORCEPROP 3 LASTPIN (-6175 2375) SIG_NAME AGND_PVPP_ABC\g
J 0
(-6165 2385);
DISPLAY 0.659574 (-6165 2385);
PAINT MONO (-6165 2385);
DISPLAY INVISIBLE (-6165 2385);
FORCEPROP 1 LAST HDL_POWER AGND_PVPP_ABC
J 1
(-6150 2250);
DISPLAY 0.617021 (-6150 2250);
PAINT GREEN (-6150 2250);
FORCEPROP 1 LAST BODY_TYPE PLUMBING
J 0
(-6220 2282);
DISPLAY 0.340426 (-6220 2282);
PAINT GREEN (-6220 2282);
DISPLAY INVISIBLE (-6220 2282);
FORCEPROP 1 LAST PATH I132
J 0
(-6100 2325);
DISPLAY 0.872340 (-6100 2325);
PAINT AQUA (-6100 2325);
DISPLAY INVISIBLE (-6100 2325);
FORCEPROP 2 LAST CDS_LIB mstr_symbols
J 0
(-6175 2325);
PAINT MONO (-6175 2325);
DISPLAY INVISIBLE (-6175 2325);
FORCEPROP 2 LAST BOM_COST PVPP_KLM_VR
J 0
(-6325 2275);
DISPLAY 1.042553 (-6325 2275);
PAINT WHITE (-6325 2275);
DISPLAY INVISIBLE (-6325 2275);
FORCEPROP 2 LAST ROOM PVPP_KLM_VR
J 0
(-6325 2275);
DISPLAY 1.042553 (-6325 2275);
PAINT GREEN (-6325 2275);
DISPLAY INVISIBLE (-6325 2275);
FORCEPROP 1 LAST VOLTAGE 0.0V
J 0
(-6220 2282);
DISPLAY 0.340426 (-6220 2282);
PAINT SKYBLUE (-6220 2282);
DISPLAY INVISIBLE (-6220 2282);
FORCEADD RES..2
R 2
(-4400 1900);
FORCEPROP 1 LAST TOLERANCE 1.0%
J 2
(-4445 1925);
DISPLAY 0.617021 (-4445 1925);
PAINT SKYBLUE (-4445 1925);
FORCEPROP 1 LAST WATTAGE 1/16W
J 2
(-4440 1875);
DISPLAY 0.617021 (-4440 1875);
PAINT SKYBLUE (-4440 1875);
FORCEPROP 0 LAST CONFIG 64.39015.6DL
J 0
(-4800 1675);
DISPLAY 0.638298 (-4800 1675);
PAINT BROWN (-4800 1675);
DISPLAY BOTH (-4800 1675);
FORCEPROP 0 LAST NEW_VALUE 3.9K
J 0
(-4800 1625);
DISPLAY 0.638298 (-4800 1625);
PAINT BROWN (-4800 1625);
DISPLAY BOTH (-4800 1625);
FORCEPROP 1 LASTPIN (-4400 1800) $PN 2
J 2
(-4405 1810);
DISPLAY 0.617021 (-4405 1810);
PAINT WHITE (-4405 1810);
FORCEPROP 1 LASTPIN (-4400 2000) $PN 1
J 2
(-4405 1962);
DISPLAY 0.617021 (-4405 1962);
PAINT WHITE (-4405 1962);
FORCEPROP 1 LAST LOCATION R7F15
J 2
(-4445 2025);
DISPLAY 0.617021 (-4445 2025);
PAINT AQUA (-4445 2025);
FORCEPROP 1 LAST PACK_TYPE 0402
J 2
(-4440 1725);
DISPLAY 0.617021 (-4440 1725);
PAINT SKYBLUE (-4440 1725);
FORCEPROP 1 LAST MATERIAL CHIP
J 2
(-4440 1825);
DISPLAY 0.617021 (-4440 1825);
PAINT SKYBLUE (-4440 1825);
FORCEPROP 1 LAST PART_NUMBER G21796-242
J 2
(-4440 1775);
DISPLAY 0.617021 (-4440 1775);
PAINT BLUE (-4440 1775);
DISPLAY INVISIBLE (-4440 1775);
FORCEPROP 1 LAST VALUE 7.87K
J 2
(-4445 1975);
DISPLAY 0.617021 (-4445 1975);
PAINT SKYBLUE (-4445 1975);
DISPLAY INVISIBLE (-4445 1975);
FORCEPROP 2 LAST ROOM PVPP_KLM_VR
J 2
(-4400 1900);
PAINT GREEN (-4400 1900);
DISPLAY INVISIBLE (-4400 1900);
FORCEPROP 2 LAST BOM_COST PVPP_KLM_VR
J 2
(-4400 1900);
PAINT WHITE (-4400 1900);
DISPLAY INVISIBLE (-4400 1900);
FORCEPROP 2 LAST CDS_LIB mstr_discrete
J 2
(-4400 1900);
PAINT MONO (-4400 1900);
DISPLAY INVISIBLE (-4400 1900);
FORCEPROP 2 LAST CDS_LOCATION R7F15
J 2
(-4445 2025);
DISPLAY 0.617021 (-4445 2025);
PAINT AQUA (-4445 2025);
DISPLAY INVISIBLE (-4445 2025);
FORCEPROP 2 LAST $SEC 1
J 0
(-4450 2125);
DISPLAY 0.680851 (-4450 2125);
PAINT MONO (-4450 2125);
DISPLAY INVISIBLE (-4450 2125);
FORCEPROP 2 LAST CDS_SEC 1
J 2
(-4300 2275);
DISPLAY 1.042553 (-4300 2275);
PAINT ORANGE (-4300 2275);
DISPLAY INVISIBLE (-4300 2275);
FORCEPROP 1 LAST PATH I134
J 2
(-4450 2075);
DISPLAY 0.978723 (-4450 2075);
PAINT WHITE (-4450 2075);
DISPLAY INVISIBLE (-4450 2075);
FORCEADD OFFPAGE..1
(-7050 3075);
FORCEPROP 2 LAST $XR1 232 
J 0
(-7422 3075);
DISPLAY 0.638298 (-7422 3075);
PAINT MONO (-7422 3075);
FORCEPROP 2 LAST $XR0 191 
J 0
(-7302 3075);
DISPLAY 0.638298 (-7302 3075);
PAINT MONO (-7302 3075);
FORCEPROP 1 LAST COMMENT_BODY TRUE
J 0
(-6925 2975);
DISPLAY 0.872340 (-6925 2975);
PAINT PEACH (-6925 2975);
DISPLAY INVISIBLE (-6925 2975);
FORCEPROP 1 LAST OFFPAGE TRUE
J 0
(-6725 2950);
PAINT GREEN (-6725 2950);
DISPLAY INVISIBLE (-6725 2950);
FORCEPROP 0 LAST TOLERANCE 1%
J 0
(-7000 3150);
PAINT SKYBLUE (-7000 3150);
DISPLAY INVISIBLE (-7000 3150);
FORCEPROP 2 LAST CDS_LIB mstr_standard
J 0
(-7050 3075);
PAINT MONO (-7050 3075);
DISPLAY INVISIBLE (-7050 3075);
FORCEPROP 2 LAST ROOM PVPP_KLM_VR
J 0
(-7600 3150);
DISPLAY 1.042553 (-7600 3150);
PAINT GREEN (-7600 3150);
DISPLAY INVISIBLE (-7600 3150);
FORCEPROP 2 LAST BOM_COST PVPP_KLM_VR
J 0
(-7875 3150);
DISPLAY 1.042553 (-7875 3150);
PAINT WHITE (-7875 3150);
DISPLAY INVISIBLE (-7875 3150);
FORCEPROP 2 LAST PATH I135
J 0
(-7300 3125);
DISPLAY 1.021277 (-7300 3125);
PAINT ORANGE (-7300 3125);
DISPLAY INVISIBLE (-7300 3125);
FORCEADD RES..2
(-6625 2450);
FORCEPROP 1 LAST LOCATION R7F14
J 0
(-6580 2575);
DISPLAY 0.617021 (-6580 2575);
PAINT AQUA (-6580 2575);
FORCEPROP 1 LAST VALUE 10.0K
J 0
(-6580 2525);
DISPLAY 0.617021 (-6580 2525);
PAINT SKYBLUE (-6580 2525);
FORCEPROP 1 LASTPIN (-6625 2550) $PN 1
J 0
(-6620 2512);
DISPLAY 0.617021 (-6620 2512);
PAINT WHITE (-6620 2512);
FORCEPROP 1 LASTPIN (-6625 2350) $PN 2
J 0
(-6620 2360);
DISPLAY 0.617021 (-6620 2360);
PAINT WHITE (-6620 2360);
FORCEPROP 1 LAST PACK_TYPE 0402
J 0
(-6585 2275);
DISPLAY 0.617021 (-6585 2275);
PAINT SKYBLUE (-6585 2275);
FORCEPROP 1 LAST TOLERANCE 1%
J 0
(-6580 2475);
DISPLAY 0.617021 (-6580 2475);
PAINT SKYBLUE (-6580 2475);
FORCEPROP 1 LAST WATTAGE 1/16W
J 0
(-6585 2425);
DISPLAY 0.617021 (-6585 2425);
PAINT SKYBLUE (-6585 2425);
FORCEPROP 1 LAST MATERIAL CHIP
J 0
(-6585 2375);
DISPLAY 0.617021 (-6585 2375);
PAINT SKYBLUE (-6585 2375);
FORCEPROP 1 LAST PART_NUMBER G21796-016
J 0
(-6610 2325);
DISPLAY 0.617021 (-6610 2325);
PAINT BLUE (-6610 2325);
FORCEPROP 0 LAST BOM SYSB_CPLD
J 0
(-6575 2775);
DISPLAY 1.042553 (-6575 2775);
PAINT ORANGE (-6575 2775);
DISPLAY INVISIBLE (-6575 2775);
FORCEPROP 2 LAST BOM_COST PVPP_KLM_VR
J 0
(-6575 2675);
DISPLAY 1.042553 (-6575 2675);
PAINT WHITE (-6575 2675);
DISPLAY INVISIBLE (-6575 2675);
FORCEPROP 2 LAST CDS_SEC 1
J 0
(-6575 2675);
DISPLAY 1.042553 (-6575 2675);
PAINT ORANGE (-6575 2675);
DISPLAY INVISIBLE (-6575 2675);
FORCEPROP 2 LAST $SEC 1
J 0
(-6575 2675);
DISPLAY 0.680851 (-6575 2675);
PAINT MONO (-6575 2675);
DISPLAY INVISIBLE (-6575 2675);
FORCEPROP 2 LAST CDS_LOCATION R7F14
J 0
(-6580 2575);
DISPLAY 0.617021 (-6580 2575);
PAINT AQUA (-6580 2575);
DISPLAY INVISIBLE (-6580 2575);
FORCEPROP 1 LAST PATH I136
J 0
(-6575 2625);
DISPLAY 0.978723 (-6575 2625);
PAINT WHITE (-6575 2625);
DISPLAY INVISIBLE (-6575 2625);
FORCEPROP 2 LAST ROOM PVPP_KLM_VR
J 0
(-6575 2675);
DISPLAY 1.042553 (-6575 2675);
PAINT GREEN (-6575 2675);
DISPLAY INVISIBLE (-6575 2675);
FORCEPROP 2 LAST CDS_LIB mstr_discrete
J 0
(-6625 2450);
PAINT MONO (-6625 2450);
DISPLAY INVISIBLE (-6625 2450);
FORCEADD CAP..1
R 2
(-6175 2650);
FORCEPROP 1 LAST VALUE 1000PF
J 2
(-6225 2700);
DISPLAY 0.617021 (-6225 2700);
PAINT SKYBLUE (-6225 2700);
FORCEPROP 1 LASTPIN (-6175 2550) $PN 2
J 2
(-6185 2530);
DISPLAY 0.617021 (-6185 2530);
PAINT WHITE (-6185 2530);
FORCEPROP 1 LAST VOLTAGE 50V
J 2
(-6225 2650);
DISPLAY 0.617021 (-6225 2650);
PAINT SKYBLUE (-6225 2650);
FORCEPROP 1 LAST TOLERANCE 10%
J 2
(-6225 2600);
DISPLAY 0.617021 (-6225 2600);
PAINT SKYBLUE (-6225 2600);
FORCEPROP 1 LAST MATERIAL EMPTY
J 2
(-6225 2550);
DISPLAY 0.617021 (-6225 2550);
PAINT RED (-6225 2550);
FORCEPROP 1 LAST PART_NUMBER A36096-046
J 2
(-6200 2500);
DISPLAY 0.617021 (-6200 2500);
PAINT BLUE (-6200 2500);
FORCEPROP 1 LAST PACK_TYPE 0402LF
J 2
(-6225 2450);
DISPLAY 0.617021 (-6225 2450);
PAINT SKYBLUE (-6225 2450);
FORCEPROP 1 LASTPIN (-6175 2750) $PN 1
J 2
(-6185 2730);
DISPLAY 0.617021 (-6185 2730);
PAINT WHITE (-6185 2730);
FORCEPROP 1 LAST LOCATION C7F8
J 2
(-6225 2750);
DISPLAY 0.617021 (-6225 2750);
PAINT AQUA (-6225 2750);
FORCEPROP 0 LAST FIN VR_1P2
J 2
(-6225 2950);
PAINT ORANGE (-6225 2950);
DISPLAY INVISIBLE (-6225 2950);
FORCEPROP 0 LAST REUSE_ID 1
J 2
(-6225 2850);
DISPLAY 1.042553 (-6225 2850);
PAINT ORANGE (-6225 2850);
DISPLAY INVISIBLE (-6225 2850);
FORCEPROP 2 LAST CDS_SEC 1
J 2
(-6225 2850);
DISPLAY 1.042553 (-6225 2850);
PAINT ORANGE (-6225 2850);
DISPLAY INVISIBLE (-6225 2850);
FORCEPROP 2 LAST $SEC 1
J 2
(-6225 2850);
DISPLAY 0.680851 (-6225 2850);
PAINT MONO (-6225 2850);
DISPLAY INVISIBLE (-6225 2850);
FORCEPROP 1 LAST PATH I140
J 2
(-6225 2800);
DISPLAY 0.978723 (-6225 2800);
PAINT WHITE (-6225 2800);
DISPLAY INVISIBLE (-6225 2800);
FORCEPROP 2 LAST CDS_LOCATION C7F8
J 2
(-6225 2750);
DISPLAY 0.617021 (-6225 2750);
PAINT AQUA (-6225 2750);
DISPLAY INVISIBLE (-6225 2750);
FORCEPROP 2 LAST CDS_LIB mstr_discrete
J 2
(-6175 2650);
PAINT MONO (-6175 2650);
DISPLAY INVISIBLE (-6175 2650);
FORCEPROP 2 LAST BOM_COST PVPP_KLM_VR
J 2
(-6175 2650);
PAINT WHITE (-6175 2650);
DISPLAY INVISIBLE (-6175 2650);
FORCEPROP 2 LAST ROOM PVPP_KLM_VR
J 2
(-6175 2650);
PAINT GREEN (-6175 2650);
DISPLAY INVISIBLE (-6175 2650);
FORCEADD GND..1
(-3700 775);
FORCEPROP 3 LASTPIN (-3700 825) SIG_NAME GND\g
J 0
(-3690 835);
DISPLAY 0.659574 (-3690 835);
PAINT MONO (-3690 835);
DISPLAY INVISIBLE (-3690 835);
FORCEPROP 1 LAST HDL_POWER GND
J 0
(-3700 1000);
DISPLAY 0.893617 (-3700 1000);
PAINT GREEN (-3700 1000);
DISPLAY INVISIBLE (-3700 1000);
FORCEPROP 1 LAST BODY_TYPE PLUMBING
J 0
(-3745 732);
DISPLAY 0.340426 (-3745 732);
PAINT GREEN (-3745 732);
DISPLAY INVISIBLE (-3745 732);
FORCEPROP 2 LAST CDS_LIB mstr_symbols
J 0
(-3700 850);
PAINT MONO (-3700 850);
DISPLAY INVISIBLE (-3700 850);
FORCEPROP 1 LAST VOLTAGE 0
J 0
(-3700 850);
PAINT SKYBLUE (-3700 850);
DISPLAY INVISIBLE (-3700 850);
FORCEPROP 1 LAST SIZE 1B
J 0
(-3625 800);
DISPLAY 0.893617 (-3625 800);
PAINT GREEN (-3625 800);
DISPLAY INVISIBLE (-3625 800);
FORCEPROP 1 LAST PATH I141
J 0
(-3625 775);
DISPLAY 0.872340 (-3625 775);
PAINT AQUA (-3625 775);
DISPLAY INVISIBLE (-3625 775);
FORCEPROP 2 LAST BOM_COST PVPP_KLM_VR
J 0
(-4600 925);
DISPLAY 1.042553 (-4600 925);
PAINT WHITE (-4600 925);
DISPLAY INVISIBLE (-4600 925);
FORCEPROP 2 LAST ROOM PVPP_KLM_VR
J 0
(-4350 925);
PAINT GREEN (-4350 925);
DISPLAY INVISIBLE (-4350 925);
FORCEADD CAP..1
(-3700 1050);
FORCEPROP 1 LAST VALUE 1000PF
J 0
(-3650 1100);
DISPLAY 0.617021 (-3650 1100);
PAINT SKYBLUE (-3650 1100);
FORCEPROP 1 LAST LOCATION C7F11
J 0
(-3650 1150);
DISPLAY 0.617021 (-3650 1150);
PAINT AQUA (-3650 1150);
FORCEPROP 1 LAST MATERIAL X7R
J 0
(-3650 950);
DISPLAY 0.617021 (-3650 950);
PAINT SKYBLUE (-3650 950);
FORCEPROP 1 LAST VOLTAGE 50V
J 0
(-3650 1050);
DISPLAY 0.617021 (-3650 1050);
PAINT SKYBLUE (-3650 1050);
FORCEPROP 1 LAST TOLERANCE 10%
J 0
(-3650 1000);
DISPLAY 0.617021 (-3650 1000);
PAINT SKYBLUE (-3650 1000);
FORCEPROP 1 LAST PART_NUMBER A36096-046
J 0
(-3650 850);
DISPLAY 0.617021 (-3650 850);
PAINT BLUE (-3650 850);
FORCEPROP 1 LASTPIN (-3700 950) $PN 2
J 0
(-3690 930);
DISPLAY 0.617021 (-3690 930);
PAINT WHITE (-3690 930);
FORCEPROP 1 LAST PACK_TYPE 0402LF
J 0
(-3650 900);
DISPLAY 0.617021 (-3650 900);
PAINT SKYBLUE (-3650 900);
FORCEPROP 1 LASTPIN (-3700 1150) $PN 1
J 0
(-3690 1130);
DISPLAY 0.617021 (-3690 1130);
PAINT WHITE (-3690 1130);
FORCEPROP 2 LAST ROOM PVPP_KLM_VR
J 0
(-3700 1050);
PAINT GREEN (-3700 1050);
DISPLAY INVISIBLE (-3700 1050);
FORCEPROP 2 LAST CDS_LIB mstr_discrete
J 2
(-3700 1050);
PAINT MONO (-3700 1050);
DISPLAY INVISIBLE (-3700 1050);
FORCEPROP 2 LAST BOM_COST PVPP_KLM_VR
J 0
(-3700 1050);
PAINT WHITE (-3700 1050);
DISPLAY INVISIBLE (-3700 1050);
FORCEPROP 2 LAST CDS_LOCATION C7F11
J 0
(-3650 1150);
DISPLAY 0.617021 (-3650 1150);
PAINT AQUA (-3650 1150);
DISPLAY INVISIBLE (-3650 1150);
FORCEPROP 1 LAST PATH I142
J 0
(-3650 1200);
DISPLAY 0.978723 (-3650 1200);
PAINT WHITE (-3650 1200);
DISPLAY INVISIBLE (-3650 1200);
FORCEPROP 2 LAST $SEC 1
J 2
(-3650 1250);
DISPLAY 0.680851 (-3650 1250);
PAINT MONO (-3650 1250);
DISPLAY INVISIBLE (-3650 1250);
FORCEPROP 2 LAST CDS_SEC 1
J 2
(-3650 1250);
DISPLAY 1.042553 (-3650 1250);
PAINT ORANGE (-3650 1250);
DISPLAY INVISIBLE (-3650 1250);
FORCEPROP 2 LAST REUSE_ID 17
J 0
(-3650 1250);
DISPLAY 1.042553 (-3650 1250);
PAINT ORANGE (-3650 1250);
DISPLAY INVISIBLE (-3650 1250);
FORCEADD RES..2
(-3875 1500);
FORCEPROP 1 LAST LOCATION R7F19
J 0
(-3830 1625);
DISPLAY 0.617021 (-3830 1625);
PAINT AQUA (-3830 1625);
FORCEPROP 1 LAST PART_NUMBER G21796-026
J 0
(-3835 1375);
DISPLAY 0.617021 (-3835 1375);
PAINT BLUE (-3835 1375);
FORCEPROP 1 LAST VALUE 1.00K
J 0
(-3830 1575);
DISPLAY 0.617021 (-3830 1575);
PAINT SKYBLUE (-3830 1575);
FORCEPROP 1 LAST PACK_TYPE 0402
J 0
(-3835 1325);
DISPLAY 0.617021 (-3835 1325);
PAINT SKYBLUE (-3835 1325);
FORCEPROP 1 LAST MATERIAL CHIP
J 0
(-3835 1425);
DISPLAY 0.617021 (-3835 1425);
PAINT SKYBLUE (-3835 1425);
FORCEPROP 1 LASTPIN (-3875 1600) $PN 1
J 0
(-3870 1562);
DISPLAY 0.617021 (-3870 1562);
PAINT WHITE (-3870 1562);
FORCEPROP 1 LAST TOLERANCE 1%
J 0
(-3830 1525);
DISPLAY 0.617021 (-3830 1525);
PAINT SKYBLUE (-3830 1525);
FORCEPROP 1 LAST WATTAGE 1/16W
J 0
(-3835 1475);
DISPLAY 0.617021 (-3835 1475);
PAINT SKYBLUE (-3835 1475);
FORCEPROP 1 LASTPIN (-3875 1400) $PN 2
J 0
(-3870 1410);
DISPLAY 0.617021 (-3870 1410);
PAINT WHITE (-3870 1410);
FORCEPROP 2 LAST SEC_TYPE 0402
J 0
(-3825 1725);
DISPLAY 1.042553 (-3825 1725);
PAINT ORANGE (-3825 1725);
DISPLAY INVISIBLE (-3825 1725);
FORCEPROP 2 LAST BOM_COST PVPP_KLM_VR
J 0
(-3815 1690);
DISPLAY 1.042553 (-3815 1690);
PAINT WHITE (-3815 1690);
DISPLAY INVISIBLE (-3815 1690);
FORCEPROP 2 LAST REUSE_ID 21
J 0
(-3825 1725);
DISPLAY 1.042553 (-3825 1725);
PAINT ORANGE (-3825 1725);
DISPLAY INVISIBLE (-3825 1725);
FORCEPROP 2 LAST SEC 1
J 0
(-3825 1725);
DISPLAY 0.680851 (-3825 1725);
PAINT MONO (-3825 1725);
DISPLAY INVISIBLE (-3825 1725);
FORCEPROP 2 LAST CDS_LOCATION R7F19
J 0
(-3830 1625);
DISPLAY 0.617021 (-3830 1625);
PAINT AQUA (-3830 1625);
DISPLAY INVISIBLE (-3830 1625);
FORCEPROP 1 LAST PATH I143
J 0
(-3825 1675);
DISPLAY 0.978723 (-3825 1675);
PAINT WHITE (-3825 1675);
DISPLAY INVISIBLE (-3825 1675);
FORCEPROP 2 LAST ROOM PVPP_KLM_VR
J 0
(-3815 1665);
PAINT GREEN (-3815 1665);
DISPLAY INVISIBLE (-3815 1665);
FORCEPROP 2 LAST CDS_LIB mstr_discrete
J 0
(-3875 1500);
PAINT MONO (-3875 1500);
DISPLAY INVISIBLE (-3875 1500);
FORCEADD CAP..1
(-5625 1000);
FORCEPROP 0 LAST GROUP PWR_MLCC_CAP
J 0
(-5569 737);
DISPLAY 0.638298 (-5569 737);
PAINT BROWN (-5569 737);
DISPLAY BOTH (-5569 737);
FORCEPROP 1 LAST PART_NUMBER E15431-001
J 0
(-5575 850);
DISPLAY 0.617021 (-5575 850);
PAINT BLUE (-5575 850);
FORCEPROP 1 LAST PACK_TYPE 0603LF
J 0
(-5575 800);
DISPLAY 0.617021 (-5575 800);
PAINT SKYBLUE (-5575 800);
FORCEPROP 1 LAST MATERIAL X6S
J 0
(-5575 900);
DISPLAY 0.617021 (-5575 900);
PAINT SKYBLUE (-5575 900);
FORCEPROP 1 LAST TOLERANCE 20%
J 0
(-5575 950);
DISPLAY 0.617021 (-5575 950);
PAINT SKYBLUE (-5575 950);
FORCEPROP 1 LAST VOLTAGE 4V
J 0
(-5575 1000);
DISPLAY 0.638298 (-5575 1000);
PAINT SKYBLUE (-5575 1000);
FORCEPROP 1 LAST VALUE 10UF
J 0
(-5575 1050);
DISPLAY 0.617021 (-5575 1050);
PAINT SKYBLUE (-5575 1050);
FORCEPROP 1 LAST LOCATION C6G5
J 0
(-5575 1100);
DISPLAY 0.617021 (-5575 1100);
PAINT AQUA (-5575 1100);
FORCEPROP 1 LASTPIN (-5625 1100) $PN 1
J 0
(-5615 1080);
DISPLAY 0.617021 (-5615 1080);
PAINT GREEN (-5615 1080);
FORCEPROP 1 LASTPIN (-5625 900) $PN 2
J 0
(-5615 880);
DISPLAY 0.617021 (-5615 880);
PAINT GREEN (-5615 880);
FORCEPROP 2 LAST BOM_COST MEM_VRD_PVPP_AB
J 0
(-5575 1150);
PAINT MONO (-5575 1150);
DISPLAY INVISIBLE (-5575 1150);
FORCEPROP 2 LAST CDS_SEC 1
J 0
(-5575 1200);
PAINT MONO (-5575 1200);
DISPLAY INVISIBLE (-5575 1200);
FORCEPROP 2 LAST $SEC 1
J 0
(-5575 1200);
PAINT MONO (-5575 1200);
DISPLAY INVISIBLE (-5575 1200);
FORCEPROP 2 LAST CDS_LOCATION C6G5
J 0
(-5575 1100);
DISPLAY 0.617021 (-5575 1100);
PAINT AQUA (-5575 1100);
DISPLAY INVISIBLE (-5575 1100);
FORCEPROP 1 LAST PATH I145
J 0
(-5575 1150);
DISPLAY 0.978723 (-5575 1150);
PAINT WHITE (-5575 1150);
DISPLAY INVISIBLE (-5575 1150);
FORCEPROP 2 LAST ROOM PVPP_KLM_VR
J 0
(-5575 1150);
PAINT MONO (-5575 1150);
DISPLAY INVISIBLE (-5575 1150);
FORCEPROP 2 LAST CDS_LIB mstr_discrete
J 0
(-5625 1000);
PAINT MONO (-5625 1000);
DISPLAY INVISIBLE (-5625 1000);
FORCEADD CAP..1
(-5350 975);
FORCEPROP 0 LAST GROUP PWR_MLCC_CAP
J 0
(-5294 687);
DISPLAY 0.638298 (-5294 687);
PAINT BROWN (-5294 687);
DISPLAY BOTH (-5294 687);
FORCEPROP 1 LAST LOCATION C4U4
J 0
(-5300 1075);
DISPLAY 0.617021 (-5300 1075);
PAINT AQUA (-5300 1075);
FORCEPROP 1 LAST VALUE 10UF
J 0
(-5300 1025);
DISPLAY 0.617021 (-5300 1025);
PAINT SKYBLUE (-5300 1025);
FORCEPROP 1 LAST VOLTAGE 4V
J 0
(-5300 975);
DISPLAY 0.638298 (-5300 975);
PAINT SKYBLUE (-5300 975);
FORCEPROP 1 LAST TOLERANCE 20%
J 0
(-5300 925);
DISPLAY 0.617021 (-5300 925);
PAINT SKYBLUE (-5300 925);
FORCEPROP 1 LASTPIN (-5350 1075) $PN 1
J 0
(-5340 1055);
DISPLAY 0.617021 (-5340 1055);
PAINT GREEN (-5340 1055);
FORCEPROP 1 LAST MATERIAL X6S
J 0
(-5300 875);
DISPLAY 0.617021 (-5300 875);
PAINT SKYBLUE (-5300 875);
FORCEPROP 1 LASTPIN (-5350 875) $PN 2
J 0
(-5340 855);
DISPLAY 0.617021 (-5340 855);
PAINT GREEN (-5340 855);
FORCEPROP 1 LAST PART_NUMBER E15431-001
J 0
(-5300 825);
DISPLAY 0.617021 (-5300 825);
PAINT BLUE (-5300 825);
FORCEPROP 1 LAST PACK_TYPE 0603LF
J 0
(-5300 775);
DISPLAY 0.617021 (-5300 775);
PAINT SKYBLUE (-5300 775);
FORCEPROP 2 LAST CDS_SEC 1
J 0
(-5300 1175);
PAINT MONO (-5300 1175);
DISPLAY INVISIBLE (-5300 1175);
FORCEPROP 2 LAST $SEC 1
J 0
(-5300 1175);
PAINT MONO (-5300 1175);
DISPLAY INVISIBLE (-5300 1175);
FORCEPROP 2 LAST BOM_COST MEM_VRD_PVPP_AB
J 0
(-5300 1125);
PAINT MONO (-5300 1125);
DISPLAY INVISIBLE (-5300 1125);
FORCEPROP 1 LAST PATH I146
J 0
(-5300 1125);
DISPLAY 0.978723 (-5300 1125);
PAINT WHITE (-5300 1125);
DISPLAY INVISIBLE (-5300 1125);
FORCEPROP 2 LAST ROOM PVPP_KLM_VR
J 0
(-5300 1125);
PAINT MONO (-5300 1125);
DISPLAY INVISIBLE (-5300 1125);
FORCEPROP 2 LAST CDS_LOCATION C4U4
J 0
(-5300 1075);
DISPLAY 0.617021 (-5300 1075);
PAINT AQUA (-5300 1075);
DISPLAY INVISIBLE (-5300 1075);
FORCEPROP 2 LAST CDS_LIB mstr_discrete
J 0
(-5350 975);
PAINT MONO (-5350 975);
DISPLAY INVISIBLE (-5350 975);
FORCEADD GND..1
(-7925 575);
FORCEPROP 3 LASTPIN (-7925 625) SIG_NAME GND\g
J 0
(-7915 635);
DISPLAY 0.659574 (-7915 635);
PAINT MONO (-7915 635);
DISPLAY INVISIBLE (-7915 635);
FORCEPROP 2 LAST ROOM PVPP_KLM_VR
J 0
(-8475 650);
PAINT ORANGE (-8475 650);
DISPLAY INVISIBLE (-8475 650);
FORCEPROP 2 LAST BOM_COST MEM_VRD_PVPP_AB
J 0
(-8250 650);
PAINT MONO (-8250 650);
DISPLAY INVISIBLE (-8250 650);
FORCEPROP 2 LAST CDS_LIB mstr_symbols
J 0
(-7925 575);
PAINT MONO (-7925 575);
DISPLAY INVISIBLE (-7925 575);
FORCEPROP 1 LAST VOLTAGE 0
J 0
(-7925 575);
PAINT SKYBLUE (-7925 575);
DISPLAY INVISIBLE (-7925 575);
FORCEPROP 1 LAST PATH I147
J 0
(-7850 575);
DISPLAY 0.872340 (-7850 575);
PAINT AQUA (-7850 575);
DISPLAY INVISIBLE (-7850 575);
FORCEPROP 1 LAST SIZE 1B
J 0
(-7850 525);
DISPLAY 0.893617 (-7850 525);
PAINT GREEN (-7850 525);
DISPLAY INVISIBLE (-7850 525);
FORCEPROP 1 LAST BODY_TYPE PLUMBING
J 0
(-7970 532);
DISPLAY 0.340426 (-7970 532);
PAINT GREEN (-7970 532);
DISPLAY INVISIBLE (-7970 532);
FORCEPROP 1 LAST HDL_POWER GND
J 0
(-7925 725);
DISPLAY 0.893617 (-7925 725);
PAINT GREEN (-7925 725);
DISPLAY INVISIBLE (-7925 725);
FORCEADD CAP..1
(-5075 975);
FORCEPROP 1 LASTPIN (-5075 1075) $PN 1
J 0
(-5065 1055);
DISPLAY 0.617021 (-5065 1055);
PAINT GREEN (-5065 1055);
FORCEPROP 1 LAST PART_NUMBER E15431-001
J 0
(-5025 825);
DISPLAY 0.617021 (-5025 825);
PAINT BLUE (-5025 825);
FORCEPROP 1 LAST PACK_TYPE 0603LF
J 0
(-5025 775);
DISPLAY 0.617021 (-5025 775);
PAINT SKYBLUE (-5025 775);
FORCEPROP 1 LAST VOLTAGE 4V
J 0
(-5025 975);
DISPLAY 0.638298 (-5025 975);
PAINT SKYBLUE (-5025 975);
FORCEPROP 1 LAST VALUE 10UF
J 0
(-5025 1025);
DISPLAY 0.617021 (-5025 1025);
PAINT SKYBLUE (-5025 1025);
FORCEPROP 1 LAST LOCATION C4U3
J 0
(-5025 1075);
DISPLAY 0.617021 (-5025 1075);
PAINT AQUA (-5025 1075);
FORCEPROP 1 LASTPIN (-5075 875) $PN 2
J 0
(-5065 855);
DISPLAY 0.617021 (-5065 855);
PAINT GREEN (-5065 855);
FORCEPROP 1 LAST MATERIAL X6S
J 0
(-5025 875);
DISPLAY 0.617021 (-5025 875);
PAINT SKYBLUE (-5025 875);
FORCEPROP 1 LAST TOLERANCE 20%
J 0
(-5025 925);
DISPLAY 0.617021 (-5025 925);
PAINT SKYBLUE (-5025 925);
FORCEPROP 0 LAST GROUP PWR_MLCC_CAP
J 0
(-5019 737);
DISPLAY 0.638298 (-5019 737);
PAINT BROWN (-5019 737);
DISPLAY BOTH (-5019 737);
FORCEPROP 2 LAST $SEC 1
J 0
(-5025 1175);
PAINT MONO (-5025 1175);
DISPLAY INVISIBLE (-5025 1175);
FORCEPROP 2 LAST CDS_SEC 1
J 0
(-5025 1175);
PAINT MONO (-5025 1175);
DISPLAY INVISIBLE (-5025 1175);
FORCEPROP 2 LAST ROOM PVPP_KLM_VR
J 0
(-5025 1125);
PAINT MONO (-5025 1125);
DISPLAY INVISIBLE (-5025 1125);
FORCEPROP 1 LAST PATH I148
J 0
(-5025 1125);
DISPLAY 0.978723 (-5025 1125);
PAINT WHITE (-5025 1125);
DISPLAY INVISIBLE (-5025 1125);
FORCEPROP 2 LAST BOM_COST MEM_VRD_PVPP_AB
J 0
(-5025 1125);
PAINT MONO (-5025 1125);
DISPLAY INVISIBLE (-5025 1125);
FORCEPROP 2 LAST CDS_LOCATION C4U3
J 0
(-5025 1075);
DISPLAY 0.617021 (-5025 1075);
PAINT AQUA (-5025 1075);
DISPLAY INVISIBLE (-5025 1075);
FORCEPROP 2 LAST CDS_LIB mstr_discrete
J 0
(-5075 975);
PAINT MONO (-5075 975);
DISPLAY INVISIBLE (-5075 975);
FORCEADD CAP..1
(-4800 975);
FORCEPROP 1 LASTPIN (-4800 1075) $PN 1
J 0
(-4790 1055);
DISPLAY 0.617021 (-4790 1055);
PAINT GREEN (-4790 1055);
FORCEPROP 1 LASTPIN (-4800 875) $PN 2
J 0
(-4790 855);
DISPLAY 0.617021 (-4790 855);
PAINT GREEN (-4790 855);
FORCEPROP 1 LAST MATERIAL X6S
J 0
(-4750 875);
DISPLAY 0.617021 (-4750 875);
PAINT SKYBLUE (-4750 875);
FORCEPROP 1 LAST PACK_TYPE 0603LF
J 0
(-4750 775);
DISPLAY 0.617021 (-4750 775);
PAINT SKYBLUE (-4750 775);
FORCEPROP 1 LAST PART_NUMBER E15431-001
J 0
(-4750 825);
DISPLAY 0.617021 (-4750 825);
PAINT BLUE (-4750 825);
FORCEPROP 1 LAST VALUE 10UF
J 0
(-4750 1025);
DISPLAY 0.617021 (-4750 1025);
PAINT SKYBLUE (-4750 1025);
FORCEPROP 1 LAST LOCATION C6F5
J 0
(-4750 1075);
DISPLAY 0.617021 (-4750 1075);
PAINT AQUA (-4750 1075);
FORCEPROP 0 LAST GROUP PWR_MLCC_CAP
J 0
(-4744 687);
DISPLAY 0.638298 (-4744 687);
PAINT BROWN (-4744 687);
DISPLAY BOTH (-4744 687);
FORCEPROP 1 LAST TOLERANCE 20%
J 0
(-4750 925);
DISPLAY 0.617021 (-4750 925);
PAINT SKYBLUE (-4750 925);
FORCEPROP 1 LAST VOLTAGE 4V
J 0
(-4750 975);
DISPLAY 0.638298 (-4750 975);
PAINT SKYBLUE (-4750 975);
FORCEPROP 2 LAST CDS_LIB mstr_discrete
J 0
(-4800 975);
PAINT MONO (-4800 975);
DISPLAY INVISIBLE (-4800 975);
FORCEPROP 2 LAST ROOM PVPP_KLM_VR
J 0
(-4750 1125);
PAINT MONO (-4750 1125);
DISPLAY INVISIBLE (-4750 1125);
FORCEPROP 1 LAST PATH I149
J 0
(-4750 1125);
DISPLAY 0.978723 (-4750 1125);
PAINT WHITE (-4750 1125);
DISPLAY INVISIBLE (-4750 1125);
FORCEPROP 2 LAST CDS_LOCATION C6F5
J 0
(-4750 1075);
DISPLAY 0.617021 (-4750 1075);
PAINT AQUA (-4750 1075);
DISPLAY INVISIBLE (-4750 1075);
FORCEPROP 2 LAST SEC 1
J 0
(-4730 1195);
DISPLAY 0.680851 (-4730 1195);
PAINT MONO (-4730 1195);
DISPLAY INVISIBLE (-4730 1195);
FORCEPROP 2 LAST SEC_TYPE 0603LF
J 0
(-4730 1195);
DISPLAY 1.021277 (-4730 1195);
PAINT ORANGE (-4730 1195);
DISPLAY INVISIBLE (-4730 1195);
FORCEPROP 2 LAST BOM_COST MEM_VRD_PVPP_AB
J 0
(-4750 1125);
PAINT MONO (-4750 1125);
DISPLAY INVISIBLE (-4750 1125);
FORCEADD CAP..2
R 2
(-3025 4450);
FORCEPROP 1 LAST MATERIAL X7R
J 2
(-3025 4300);
DISPLAY 0.617021 (-3025 4300);
PAINT SKYBLUE (-3025 4300);
FORCEPROP 1 LAST TOLERANCE 10%
J 0
(-3025 4300);
DISPLAY 0.617021 (-3025 4300);
PAINT SKYBLUE (-3025 4300);
FORCEPROP 1 LAST VALUE 0.1UF
J 0
(-3025 4350);
DISPLAY 0.617021 (-3025 4350);
PAINT SKYBLUE (-3025 4350);
FORCEPROP 1 LAST PACK_TYPE 0603LF
J 1
(-3025 4250);
DISPLAY 0.617021 (-3025 4250);
PAINT SKYBLUE (-3025 4250);
FORCEPROP 1 LAST VOLTAGE 25V
J 2
(-3025 4350);
DISPLAY 0.617021 (-3025 4350);
PAINT SKYBLUE (-3025 4350);
FORCEPROP 1 LASTPIN (-3125 4450) $PN 2
J 2
(-3110 4465);
DISPLAY 0.617021 (-3110 4465);
PAINT WHITE (-3110 4465);
FORCEPROP 1 LASTPIN (-2925 4450) $PN 1
J 2
(-2915 4465);
DISPLAY 0.617021 (-2915 4465);
PAINT WHITE (-2915 4465);
FORCEPROP 1 LAST LOCATION C7F4
J 1
(-3025 4550);
DISPLAY 0.617021 (-3025 4550);
PAINT AQUA (-3025 4550);
FORCEPROP 1 LAST PART_NUMBER 602433-020
J 1
(-3025 4500);
DISPLAY 0.617021 (-3025 4500);
PAINT BLUE (-3025 4500);
FORCEPROP 1 LAST PATH I159
J 2
(-3025 4650);
DISPLAY 0.978723 (-3025 4650);
PAINT WHITE (-3025 4650);
DISPLAY INVISIBLE (-3025 4650);
FORCEPROP 2 LAST $SEC 1
J 0
(-3025 4700);
DISPLAY 0.680851 (-3025 4700);
PAINT MONO (-3025 4700);
DISPLAY INVISIBLE (-3025 4700);
FORCEPROP 2 LAST BOM_COST PVPP_KLM_VR
J 0
(-3070 4610);
DISPLAY 1.042553 (-3070 4610);
PAINT WHITE (-3070 4610);
DISPLAY INVISIBLE (-3070 4610);
FORCEPROP 0 LAST SPOF TRUE
J 0
(-3025 4650);
DISPLAY 1.021277 (-3025 4650);
PAINT ORANGE (-3025 4650);
DISPLAY INVISIBLE (-3025 4650);
FORCEPROP 2 LAST CDS_SEC 1
J 0
(-3070 4660);
DISPLAY 1.042553 (-3070 4660);
PAINT ORANGE (-3070 4660);
DISPLAY INVISIBLE (-3070 4660);
FORCEPROP 2 LAST REUSE_ID 27
J 0
(-3025 4700);
DISPLAY 1.042553 (-3025 4700);
PAINT ORANGE (-3025 4700);
DISPLAY INVISIBLE (-3025 4700);
FORCEPROP 2 LAST CDS_LOCATION C7F4
J 1
(-3025 4550);
DISPLAY 0.617021 (-3025 4550);
PAINT AQUA (-3025 4550);
DISPLAY INVISIBLE (-3025 4550);
FORCEPROP 2 LAST ROOM PVPP_KLM_VR
J 2
(-3025 4575);
DISPLAY 0.765957 (-3025 4575);
PAINT GREEN (-3025 4575);
DISPLAY INVISIBLE (-3025 4575);
FORCEPROP 2 LAST CDS_LIB mstr_discrete
J 0
(-3025 4450);
PAINT MONO (-3025 4450);
DISPLAY INVISIBLE (-3025 4450);
FORCEADD GND..1
(-4700 4150);
FORCEPROP 3 LASTPIN (-4700 4200) SIG_NAME GND\g
J 0
(-4690 4210);
DISPLAY 0.659574 (-4690 4210);
PAINT MONO (-4690 4210);
DISPLAY INVISIBLE (-4690 4210);
FORCEPROP 1 LAST HDL_POWER GND
J 0
(-4700 4300);
DISPLAY 0.872340 (-4700 4300);
PAINT GREEN (-4700 4300);
DISPLAY INVISIBLE (-4700 4300);
FORCEPROP 1 LAST BODY_TYPE PLUMBING
J 0
(-4745 4107);
DISPLAY 0.340426 (-4745 4107);
PAINT GREEN (-4745 4107);
DISPLAY INVISIBLE (-4745 4107);
FORCEPROP 1 LAST SIZE 1B
J 0
(-4625 4100);
DISPLAY 0.872340 (-4625 4100);
PAINT GREEN (-4625 4100);
DISPLAY INVISIBLE (-4625 4100);
FORCEPROP 1 LAST PATH I160
J 0
(-4625 4150);
DISPLAY 0.872340 (-4625 4150);
PAINT AQUA (-4625 4150);
DISPLAY INVISIBLE (-4625 4150);
FORCEPROP 2 LAST CDS_LIB mstr_symbols
J 0
(-4700 4150);
PAINT MONO (-4700 4150);
DISPLAY INVISIBLE (-4700 4150);
FORCEPROP 1 LAST VOLTAGE 0
J 0
(-4700 4150);
PAINT SKYBLUE (-4700 4150);
DISPLAY INVISIBLE (-4700 4150);
FORCEPROP 2 LAST BOM_COST PVPP_KLM_VR
J 0
(-5550 4225);
DISPLAY 1.042553 (-5550 4225);
PAINT WHITE (-5550 4225);
DISPLAY INVISIBLE (-5550 4225);
FORCEPROP 2 LAST ROOM PVPP_KLM_VR
J 0
(-5275 4225);
DISPLAY 1.042553 (-5275 4225);
PAINT GREEN (-5275 4225);
DISPLAY INVISIBLE (-5275 4225);
FORCEADD CAP..1
(-4700 4400);
FORCEPROP 1 LAST PART_NUMBER D97712-011
J 0
(-4650 4250);
DISPLAY 0.617021 (-4650 4250);
PAINT BLUE (-4650 4250);
FORCEPROP 1 LAST MATERIAL X6S
J 0
(-4650 4300);
DISPLAY 0.617021 (-4650 4300);
PAINT SKYBLUE (-4650 4300);
FORCEPROP 1 LAST TOLERANCE 10%
J 0
(-4650 4350);
DISPLAY 0.617021 (-4650 4350);
PAINT SKYBLUE (-4650 4350);
FORCEPROP 1 LASTPIN (-4700 4300) $PN 2
J 0
(-4690 4280);
DISPLAY 0.617021 (-4690 4280);
PAINT WHITE (-4690 4280);
FORCEPROP 1 LASTPIN (-4700 4500) $PN 1
J 0
(-4690 4480);
DISPLAY 0.617021 (-4690 4480);
PAINT WHITE (-4690 4480);
FORCEPROP 1 LAST VOLTAGE 16V
J 0
(-4650 4400);
DISPLAY 0.617021 (-4650 4400);
PAINT SKYBLUE (-4650 4400);
FORCEPROP 1 LAST VALUE 1.0UF
J 0
(-4650 4450);
DISPLAY 0.617021 (-4650 4450);
PAINT SKYBLUE (-4650 4450);
FORCEPROP 1 LAST LOCATION C3T10
J 0
(-4650 4500);
DISPLAY 0.617021 (-4650 4500);
PAINT AQUA (-4650 4500);
FORCEPROP 1 LAST PACK_TYPE 0402
J 0
(-4650 4200);
DISPLAY 0.617021 (-4650 4200);
PAINT SKYBLUE (-4650 4200);
FORCEPROP 2 LAST CDS_LIB mstr_discrete
J 0
(-4700 4400);
PAINT MONO (-4700 4400);
DISPLAY INVISIBLE (-4700 4400);
FORCEPROP 2 LAST CDS_LOCATION C3T10
J 0
(-4650 4500);
DISPLAY 0.617021 (-4650 4500);
PAINT AQUA (-4650 4500);
DISPLAY INVISIBLE (-4650 4500);
FORCEPROP 1 LAST PATH I161
J 0
(-4650 4550);
DISPLAY 0.978723 (-4650 4550);
PAINT WHITE (-4650 4550);
DISPLAY INVISIBLE (-4650 4550);
FORCEPROP 2 LAST BOM_COST PVPP_KLM_VR
J 0
(-4700 4400);
PAINT WHITE (-4700 4400);
DISPLAY INVISIBLE (-4700 4400);
FORCEPROP 2 LAST ROOM PVPP_KLM_VR
J 0
(-4700 4400);
PAINT GREEN (-4700 4400);
DISPLAY INVISIBLE (-4700 4400);
FORCEPROP 0 LAST REUSE_ID 1
J 0
(-4650 4600);
DISPLAY 1.042553 (-4650 4600);
PAINT ORANGE (-4650 4600);
DISPLAY INVISIBLE (-4650 4600);
FORCEPROP 2 LAST CDS_SEC 1
J 0
(-4650 4600);
DISPLAY 1.042553 (-4650 4600);
PAINT ORANGE (-4650 4600);
DISPLAY INVISIBLE (-4650 4600);
FORCEPROP 2 LAST $SEC 1
J 0
(-4650 4600);
DISPLAY 0.680851 (-4650 4600);
PAINT MONO (-4650 4600);
DISPLAY INVISIBLE (-4650 4600);
FORCEPROP 0 LAST FIN VR_1P2
J 0
(-4650 4700);
PAINT ORANGE (-4650 4700);
DISPLAY INVISIBLE (-4650 4700);
FORCEADD FERRITE..1
(-7300 4550);
FORCEPROP 1 LAST VALUE 22
J 2
(-7320 4450);
DISPLAY 0.617021 (-7320 4450);
PAINT SKYBLUE (-7320 4450);
FORCEPROP 1 LAST PART_NUMBER 656554-051
J 0
(-7395 4665);
DISPLAY 0.617021 (-7395 4665);
PAINT BLUE (-7395 4665);
FORCEPROP 1 LAST PACK_TYPE SM
J 0
(-7220 4450);
DISPLAY 0.617021 (-7220 4450);
PAINT SKYBLUE (-7220 4450);
FORCEPROP 1 LASTPIN (-7200 4550) $PN 2
J 0
(-7220 4560);
DISPLAY 0.617021 (-7220 4560);
PAINT WHITE (-7220 4560);
FORCEPROP 1 LASTPIN (-7400 4550) $PN 1
J 2
(-7365 4560);
DISPLAY 0.617021 (-7365 4560);
PAINT WHITE (-7365 4560);
FORCEPROP 1 LAST MATERIAL FB
J 0
(-7295 4450);
DISPLAY 0.617021 (-7295 4450);
PAINT SKYBLUE (-7295 4450);
FORCEPROP 1 LAST LOCATION FB7F1
J 0
(-7395 4605);
DISPLAY 0.617021 (-7395 4605);
PAINT AQUA (-7395 4605);
FORCEPROP 2 LAST SEC_TYPE SM
J 0
(-7375 4775);
DISPLAY 1.659574 (-7375 4775);
PAINT ORANGE (-7375 4775);
DISPLAY INVISIBLE (-7375 4775);
FORCEPROP 0 LAST TOLERANCE 1%
J 0
(-7375 4700);
PAINT SKYBLUE (-7375 4700);
DISPLAY INVISIBLE (-7375 4700);
FORCEPROP 2 LAST SEC 1
J 0
(-7375 4775);
DISPLAY 1.106383 (-7375 4775);
PAINT MONO (-7375 4775);
DISPLAY INVISIBLE (-7375 4775);
FORCEPROP 1 LAST PATH I162
J 0
(-7395 4715);
DISPLAY 0.872340 (-7395 4715);
PAINT PURPLE (-7395 4715);
DISPLAY INVISIBLE (-7395 4715);
FORCEPROP 2 LAST ROOM PVPP_KLM_VR
J 0
(-7375 4700);
DISPLAY 1.659574 (-7375 4700);
PAINT GREEN (-7375 4700);
DISPLAY INVISIBLE (-7375 4700);
FORCEPROP 2 LAST CDS_LOCATION FB7F1
J 0
(-7395 4605);
DISPLAY 0.617021 (-7395 4605);
PAINT AQUA (-7395 4605);
DISPLAY INVISIBLE (-7395 4605);
FORCEPROP 2 LAST CDS_LIB mstr_discrete
J 0
(-7300 4550);
PAINT MONO (-7300 4550);
DISPLAY INVISIBLE (-7300 4550);
FORCEADD P12V_STBY..1
(-7500 4650);
FORCEPROP 3 LASTPIN (-7500 4600) SIG_NAME P12V_STBY\g
J 0
(-7490 4610);
DISPLAY 0.659574 (-7490 4610);
PAINT MONO (-7490 4610);
DISPLAY INVISIBLE (-7490 4610);
FORCEPROP 1 LAST HDL_POWER P12V_STBY
J 0
(-7800 4525);
DISPLAY 0.872340 (-7800 4525);
PAINT ORANGE (-7800 4525);
DISPLAY INVISIBLE (-7800 4525);
FORCEPROP 1 LAST BODY_TYPE PLUMBING
J 0
(-7545 4607);
DISPLAY 0.340426 (-7545 4607);
PAINT GREEN (-7545 4607);
DISPLAY INVISIBLE (-7545 4607);
FORCEPROP 1 LAST PATH I163
J 0
(-7455 4652);
DISPLAY 0.340426 (-7455 4652);
PAINT GREEN (-7455 4652);
DISPLAY INVISIBLE (-7455 4652);
FORCEPROP 1 LAST SIZE 1B
J 0
(-7455 4672);
DISPLAY 0.340426 (-7455 4672);
PAINT GREEN (-7455 4672);
DISPLAY INVISIBLE (-7455 4672);
FORCEPROP 1 LAST VOLTAGE 12.0V
J 0
(-7545 4607);
DISPLAY 0.340426 (-7545 4607);
PAINT SKYBLUE (-7545 4607);
DISPLAY INVISIBLE (-7545 4607);
FORCEPROP 2 LAST CDS_LIB mstr_symbols
J 0
(-7500 4650);
PAINT ORANGE (-7500 4650);
DISPLAY INVISIBLE (-7500 4650);
FORCEADD AGND_SCSI..1
(-1000 1250);
FORCEPROP 3 LASTPIN (-1000 1300) SIG_NAME AGND_PVPP_ABC\g
J 0
(-990 1310);
DISPLAY 0.659574 (-990 1310);
PAINT MONO (-990 1310);
DISPLAY INVISIBLE (-990 1310);
FORCEPROP 1 LAST HDL_POWER AGND_PVPP_ABC
J 1
(-925 1175);
DISPLAY 0.617021 (-925 1175);
PAINT GREEN (-925 1175);
FORCEPROP 1 LAST BODY_TYPE PLUMBING
J 0
(-1045 1207);
DISPLAY 0.340426 (-1045 1207);
PAINT GREEN (-1045 1207);
DISPLAY INVISIBLE (-1045 1207);
FORCEPROP 2 LAST ROOM PVPP_KLM_VR
J 0
(-1150 1200);
DISPLAY 1.042553 (-1150 1200);
PAINT GREEN (-1150 1200);
DISPLAY INVISIBLE (-1150 1200);
FORCEPROP 2 LAST BOM_COST PVPP_KLM_VR
J 0
(-1150 1200);
DISPLAY 1.042553 (-1150 1200);
PAINT WHITE (-1150 1200);
DISPLAY INVISIBLE (-1150 1200);
FORCEPROP 1 LAST VOLTAGE 0.0V
J 0
(-1045 1207);
DISPLAY 0.340426 (-1045 1207);
PAINT SKYBLUE (-1045 1207);
DISPLAY INVISIBLE (-1045 1207);
FORCEPROP 1 LAST PATH I165
J 0
(-925 1250);
DISPLAY 0.872340 (-925 1250);
PAINT AQUA (-925 1250);
DISPLAY INVISIBLE (-925 1250);
FORCEPROP 2 LAST CDS_LIB mstr_symbols
J 0
(-1000 1250);
PAINT MONO (-1000 1250);
DISPLAY INVISIBLE (-1000 1250);
FORCEADD RES..2
(-1000 2250);
FORCEPROP 1 LASTPIN (-1000 2150) $PN 2
J 0
(-995 2160);
DISPLAY 0.617021 (-995 2160);
PAINT WHITE (-995 2160);
FORCEPROP 1 LASTPIN (-1000 2350) $PN 1
J 0
(-995 2312);
DISPLAY 0.617021 (-995 2312);
PAINT WHITE (-995 2312);
FORCEPROP 1 LAST TOLERANCE 1%
J 0
(-955 2275);
DISPLAY 0.617021 (-955 2275);
PAINT SKYBLUE (-955 2275);
FORCEPROP 1 LAST PART_NUMBER G21796-040
J 0
(-985 2075);
DISPLAY 0.617021 (-985 2075);
PAINT BLUE (-985 2075);
FORCEPROP 1 LAST MATERIAL CHIP
J 0
(-960 2125);
DISPLAY 0.617021 (-960 2125);
PAINT SKYBLUE (-960 2125);
FORCEPROP 1 LAST PACK_TYPE 0402
J 0
(-960 2175);
DISPLAY 0.617021 (-960 2175);
PAINT SKYBLUE (-960 2175);
FORCEPROP 1 LAST WATTAGE 1/16W
J 0
(-960 2225);
DISPLAY 0.617021 (-960 2225);
PAINT SKYBLUE (-960 2225);
FORCEPROP 1 LAST VALUE 20.0K
J 0
(-955 2325);
DISPLAY 0.617021 (-955 2325);
PAINT SKYBLUE (-955 2325);
FORCEPROP 1 LAST LOCATION R7F13
J 0
(-955 2375);
DISPLAY 0.617021 (-955 2375);
PAINT AQUA (-955 2375);
FORCEPROP 2 LAST CDS_LIB mstr_discrete
J 0
(-1000 2250);
PAINT MONO (-1000 2250);
DISPLAY INVISIBLE (-1000 2250);
FORCEPROP 2 LAST CDS_LOCATION R7F13
J 0
(-955 2375);
DISPLAY 0.617021 (-955 2375);
PAINT AQUA (-955 2375);
DISPLAY INVISIBLE (-955 2375);
FORCEPROP 2 LAST ROOM PVPP_KLM_VR
J 0
(-955 2405);
PAINT GREEN (-955 2405);
DISPLAY INVISIBLE (-955 2405);
FORCEPROP 1 LAST PATH I167
J 0
(-950 2425);
DISPLAY 0.978723 (-950 2425);
PAINT WHITE (-950 2425);
DISPLAY INVISIBLE (-950 2425);
FORCEPROP 2 LAST $SEC 1
J 0
(-950 2475);
DISPLAY 0.680851 (-950 2475);
PAINT MONO (-950 2475);
DISPLAY INVISIBLE (-950 2475);
FORCEPROP 2 LAST CDS_SEC 1
J 0
(-950 2475);
DISPLAY 1.042553 (-950 2475);
PAINT ORANGE (-950 2475);
DISPLAY INVISIBLE (-950 2475);
FORCEPROP 2 LAST BOM_COST PVPP_KLM_VR
J 0
(-955 2430);
DISPLAY 1.042553 (-955 2430);
PAINT WHITE (-955 2430);
DISPLAY INVISIBLE (-955 2430);
FORCEPROP 2 LAST REUSE_ID 9
J 0
(-950 2475);
DISPLAY 1.042553 (-950 2475);
PAINT ORANGE (-950 2475);
DISPLAY INVISIBLE (-950 2475);
FORCEPROP 0 LAST SPOF TRUE
J 0
(-950 2475);
DISPLAY 1.021277 (-950 2475);
PAINT ORANGE (-950 2475);
DISPLAY INVISIBLE (-950 2475);
FORCEADD RES..1
R 5
(-1000 3175);
FORCEPROP 1 LAST PART_NUMBER G21497-005
J 0
(-975 2975);
DISPLAY 0.617021 (-975 2975);
PAINT BLUE (-975 2975);
FORCEPROP 1 LAST PACK_TYPE 0402
J 0
(-975 3025);
DISPLAY 0.617021 (-975 3025);
PAINT SKYBLUE (-975 3025);
FORCEPROP 1 LAST MATERIAL CHIP
J 0
(-975 3075);
DISPLAY 0.617021 (-975 3075);
PAINT SKYBLUE (-975 3075);
FORCEPROP 1 LAST TOLERANCE 5%
J 0
(-925 3125);
DISPLAY 0.617021 (-925 3125);
PAINT SKYBLUE (-925 3125);
FORCEPROP 1 LAST WATTAGE 1/16W
J 0
(-975 3175);
DISPLAY 0.617021 (-975 3175);
PAINT SKYBLUE (-975 3175);
FORCEPROP 1 LAST VALUE 0.0
J 0
(-950 3225);
DISPLAY 0.617021 (-950 3225);
PAINT SKYBLUE (-950 3225);
FORCEPROP 1 LAST LOCATION R7F12
J 0
(-850 3125);
DISPLAY 0.617021 (-850 3125);
PAINT AQUA (-850 3125);
FORCEPROP 1 LASTPIN (-1000 3075) $PN 2
J 0
(-988 3113);
DISPLAY 0.617021 (-988 3113);
PAINT ORANGE (-988 3113);
FORCEPROP 1 LASTPIN (-1000 3275) $PN 1
J 0
(-988 3263);
DISPLAY 0.617021 (-988 3263);
PAINT ORANGE (-988 3263);
FORCEPROP 2 LAST SEC 1
J 0
(-925 3325);
DISPLAY 0.680851 (-925 3325);
PAINT MONO (-925 3325);
DISPLAY INVISIBLE (-925 3325);
FORCEPROP 0 LAST SPOF TRUE
J 0
(-950 3325);
DISPLAY 1.021277 (-950 3325);
PAINT ORANGE (-950 3325);
DISPLAY INVISIBLE (-950 3325);
FORCEPROP 2 LAST SEC_TYPE 0402
J 0
(-925 3325);
DISPLAY 1.021277 (-925 3325);
PAINT ORANGE (-925 3325);
DISPLAY INVISIBLE (-925 3325);
FORCEPROP 2 LAST ROOM PVPP_KLM_VR
R 3
J 0
(-850 3225);
DISPLAY 1.659574 (-850 3225);
PAINT GREEN (-850 3225);
DISPLAY INVISIBLE (-850 3225);
FORCEPROP 1 LAST PATH I168
R 3
J 0
(-850 3225);
DISPLAY 0.978723 (-850 3225);
PAINT WHITE (-850 3225);
DISPLAY INVISIBLE (-850 3225);
FORCEPROP 2 LAST CDS_LIB mstr_discrete
J 0
(-1000 3175);
PAINT ORANGE (-1000 3175);
DISPLAY INVISIBLE (-1000 3175);
FORCEPROP 2 LAST CDS_LOCATION R7F12
J 0
(-900 3125);
DISPLAY 0.617021 (-900 3125);
PAINT AQUA (-900 3125);
DISPLAY INVISIBLE (-900 3125);
FORCEADD GND..1
(-1250 625);
FORCEPROP 3 LASTPIN (-1250 675) SIG_NAME GND\g
J 0
(-1240 685);
DISPLAY 0.659574 (-1240 685);
PAINT MONO (-1240 685);
DISPLAY INVISIBLE (-1240 685);
FORCEPROP 1 LAST HDL_POWER GND
J 0
(-1250 775);
DISPLAY 0.872340 (-1250 775);
PAINT GREEN (-1250 775);
DISPLAY INVISIBLE (-1250 775);
FORCEPROP 1 LAST BODY_TYPE PLUMBING
J 0
(-1295 582);
DISPLAY 0.340426 (-1295 582);
PAINT GREEN (-1295 582);
DISPLAY INVISIBLE (-1295 582);
FORCEPROP 2 LAST CDS_LIB mstr_symbols
J 0
(-1250 625);
PAINT MONO (-1250 625);
DISPLAY INVISIBLE (-1250 625);
FORCEPROP 1 LAST SIZE 1B
J 0
(-1175 575);
DISPLAY 0.872340 (-1175 575);
PAINT AQUA (-1175 575);
DISPLAY INVISIBLE (-1175 575);
FORCEPROP 1 LAST VOLTAGE 0
J 0
(-1250 625);
PAINT SKYBLUE (-1250 625);
DISPLAY INVISIBLE (-1250 625);
FORCEPROP 1 LAST PATH I169
J 0
(-1175 625);
DISPLAY 0.872340 (-1175 625);
PAINT AQUA (-1175 625);
DISPLAY INVISIBLE (-1175 625);
FORCEPROP 2 LAST ROOM PVPP_KLM_VR
J 0
(-1825 700);
DISPLAY 1.042553 (-1825 700);
PAINT GREEN (-1825 700);
DISPLAY INVISIBLE (-1825 700);
FORCEPROP 2 LAST BOM_COST PVPP_KLM_VR
J 0
(-2100 700);
DISPLAY 1.042553 (-2100 700);
PAINT WHITE (-2100 700);
DISPLAY INVISIBLE (-2100 700);
FORCEADD RES..1
(-950 725);
FORCEPROP 1 LAST WATTAGE 1/16W
J 2
(-950 575);
DISPLAY 0.617021 (-950 575);
PAINT SKYBLUE (-950 575);
FORCEPROP 1 LAST MATERIAL CHIP
J 0
(-950 575);
DISPLAY 0.617021 (-950 575);
PAINT SKYBLUE (-950 575);
FORCEPROP 1 LASTPIN (-850 725) $PN 2
J 0
(-888 737);
DISPLAY 0.617021 (-888 737);
PAINT WHITE (-888 737);
FORCEPROP 1 LAST TOLERANCE 5%
J 0
(-950 625);
DISPLAY 0.617021 (-950 625);
PAINT SKYBLUE (-950 625);
FORCEPROP 1 LAST VALUE 0.0
J 2
(-975 625);
DISPLAY 0.617021 (-975 625);
PAINT SKYBLUE (-975 625);
FORCEPROP 1 LAST PACK_TYPE 0402
J 0
(-1025 525);
DISPLAY 0.617021 (-1025 525);
PAINT SKYBLUE (-1025 525);
FORCEPROP 1 LAST LOCATION R7F35
J 0
(-1000 775);
DISPLAY 0.617021 (-1000 775);
PAINT AQUA (-1000 775);
FORCEPROP 1 LAST PART_NUMBER G21497-005
J 0
(-1075 675);
DISPLAY 0.617021 (-1075 675);
PAINT BLUE (-1075 675);
FORCEPROP 1 LASTPIN (-1050 725) $PN 1
J 0
(-1038 737);
DISPLAY 0.617021 (-1038 737);
PAINT WHITE (-1038 737);
FORCEPROP 2 LAST ROOM PVPP_KLM_VR
J 0
(-1000 800);
PAINT GREEN (-1000 800);
DISPLAY INVISIBLE (-1000 800);
FORCEPROP 1 LAST PATH I170
J 0
(-1000 875);
DISPLAY 0.978723 (-1000 875);
PAINT WHITE (-1000 875);
DISPLAY INVISIBLE (-1000 875);
FORCEPROP 2 LAST $SEC 1
J 0
(-985 930);
PAINT MONO (-985 930);
DISPLAY INVISIBLE (-985 930);
FORCEPROP 2 LAST CDS_SEC 1
J 0
(-990 910);
PAINT MONO (-990 910);
DISPLAY INVISIBLE (-990 910);
FORCEPROP 2 LAST CDS_LIB mstr_discrete
J 0
(-950 725);
PAINT MONO (-950 725);
DISPLAY INVISIBLE (-950 725);
FORCEADD AGND_SCSI..1
(-700 625);
FORCEPROP 3 LASTPIN (-700 675) SIG_NAME AGND_PVPP_ABC\g
J 0
(-690 685);
DISPLAY 0.659574 (-690 685);
PAINT MONO (-690 685);
DISPLAY INVISIBLE (-690 685);
FORCEPROP 1 LAST HDL_POWER AGND_PVPP_ABC
J 1
(-625 550);
DISPLAY 0.617021 (-625 550);
PAINT GREEN (-625 550);
FORCEPROP 1 LAST BODY_TYPE PLUMBING
J 0
(-745 582);
DISPLAY 0.340426 (-745 582);
PAINT GREEN (-745 582);
DISPLAY INVISIBLE (-745 582);
FORCEPROP 1 LAST VOLTAGE 0.0V
J 0
(-745 582);
DISPLAY 0.340426 (-745 582);
PAINT SKYBLUE (-745 582);
DISPLAY INVISIBLE (-745 582);
FORCEPROP 2 LAST CDS_LIB mstr_symbols
J 0
(-700 625);
PAINT ORANGE (-700 625);
DISPLAY INVISIBLE (-700 625);
FORCEPROP 1 LAST PATH I171
J 0
(-625 625);
DISPLAY 0.872340 (-625 625);
PAINT AQUA (-625 625);
DISPLAY INVISIBLE (-625 625);
FORCEPROP 2 LAST BOM_COST PVPP_KLM_VR
J 0
(-850 575);
DISPLAY 1.042553 (-850 575);
PAINT WHITE (-850 575);
DISPLAY INVISIBLE (-850 575);
FORCEPROP 2 LAST ROOM PVPP_KLM_VR
J 0
(-850 575);
DISPLAY 1.042553 (-850 575);
PAINT GREEN (-850 575);
DISPLAY INVISIBLE (-850 575);
FORCEADD GND..1
(-2300 3400);
FORCEPROP 3 LASTPIN (-2300 3450) SIG_NAME GND\g
J 0
(-2290 3460);
DISPLAY 0.659574 (-2290 3460);
PAINT MONO (-2290 3460);
DISPLAY INVISIBLE (-2290 3460);
FORCEPROP 1 LAST HDL_POWER GND
J 0
(-2300 3625);
DISPLAY 0.893617 (-2300 3625);
PAINT GREEN (-2300 3625);
DISPLAY INVISIBLE (-2300 3625);
FORCEPROP 1 LAST BODY_TYPE PLUMBING
J 0
(-2345 3357);
DISPLAY 0.340426 (-2345 3357);
PAINT GREEN (-2345 3357);
DISPLAY INVISIBLE (-2345 3357);
FORCEPROP 1 LAST VOLTAGE 0
J 0
(-2300 3475);
PAINT SKYBLUE (-2300 3475);
DISPLAY INVISIBLE (-2300 3475);
FORCEPROP 2 LAST CDS_LIB mstr_symbols
J 0
(-2300 3475);
PAINT MONO (-2300 3475);
DISPLAY INVISIBLE (-2300 3475);
FORCEPROP 1 LAST SIZE 1B
J 0
(-2225 3425);
DISPLAY 0.893617 (-2225 3425);
PAINT GREEN (-2225 3425);
DISPLAY INVISIBLE (-2225 3425);
FORCEPROP 1 LAST PATH I173
J 0
(-2225 3400);
DISPLAY 0.872340 (-2225 3400);
PAINT AQUA (-2225 3400);
DISPLAY INVISIBLE (-2225 3400);
FORCEPROP 2 LAST ROOM PVPP_KLM_VR
J 0
(-2950 3550);
PAINT GREEN (-2950 3550);
DISPLAY INVISIBLE (-2950 3550);
FORCEPROP 2 LAST BOM_COST PVPP_KLM_VR
J 0
(-3200 3550);
DISPLAY 1.042553 (-3200 3550);
PAINT WHITE (-3200 3550);
DISPLAY INVISIBLE (-3200 3550);
FORCEADD RES..2
(-2300 3600);
FORCEPROP 1 LAST WATTAGE 1/16W
J 0
(-2185 3525);
DISPLAY 0.617021 (-2185 3525);
PAINT SKYBLUE (-2185 3525);
FORCEPROP 1 LAST PACK_TYPE 0402
J 0
(-2185 3475);
DISPLAY 0.617021 (-2185 3475);
PAINT SKYBLUE (-2185 3475);
FORCEPROP 1 LAST MATERIAL EMPTY
J 0
(-2185 3575);
DISPLAY 0.617021 (-2185 3575);
PAINT RED (-2185 3575);
FORCEPROP 1 LAST LOCATION R7F7
J 0
(-2255 3700);
DISPLAY 0.617021 (-2255 3700);
PAINT AQUA (-2255 3700);
FORCEPROP 1 LAST VALUE 2.2
J 0
(-2180 3675);
DISPLAY 0.617021 (-2180 3675);
PAINT SKYBLUE (-2180 3675);
FORCEPROP 1 LAST TOLERANCE 5%
J 0
(-2180 3625);
DISPLAY 0.617021 (-2180 3625);
PAINT SKYBLUE (-2180 3625);
FORCEPROP 1 LASTPIN (-2300 3700) $PN 1
J 0
(-2295 3662);
DISPLAY 0.617021 (-2295 3662);
PAINT WHITE (-2295 3662);
FORCEPROP 1 LASTPIN (-2300 3500) $PN 2
J 0
(-2295 3510);
DISPLAY 0.617021 (-2295 3510);
PAINT WHITE (-2295 3510);
FORCEPROP 1 LAST PART_NUMBER G21497-016
J 0
(-2185 3425);
DISPLAY 0.617021 (-2185 3425);
PAINT BLUE (-2185 3425);
FORCEPROP 2 LAST REUSE_ID 29
J 0
(-2250 3825);
DISPLAY 1.042553 (-2250 3825);
PAINT ORANGE (-2250 3825);
DISPLAY INVISIBLE (-2250 3825);
FORCEPROP 2 LAST CDS_SEC 1
J 0
(-2250 3825);
DISPLAY 1.042553 (-2250 3825);
PAINT ORANGE (-2250 3825);
DISPLAY INVISIBLE (-2250 3825);
FORCEPROP 2 LAST $SEC 1
J 0
(-2250 3825);
DISPLAY 0.680851 (-2250 3825);
PAINT MONO (-2250 3825);
DISPLAY INVISIBLE (-2250 3825);
FORCEPROP 2 LAST BOM_COST PVPP_KLM_VR
J 0
(-2250 3775);
DISPLAY 1.042553 (-2250 3775);
PAINT WHITE (-2250 3775);
DISPLAY INVISIBLE (-2250 3775);
FORCEPROP 1 LAST PATH I174
J 0
(-2250 3775);
DISPLAY 0.978723 (-2250 3775);
PAINT WHITE (-2250 3775);
DISPLAY INVISIBLE (-2250 3775);
FORCEPROP 2 LAST ROOM PVPP_KLM_VR
J 0
(-2250 3750);
PAINT GREEN (-2250 3750);
DISPLAY INVISIBLE (-2250 3750);
FORCEPROP 2 LAST CDS_LOCATION R7F7
J 0
(-2255 3700);
DISPLAY 0.617021 (-2255 3700);
PAINT AQUA (-2255 3700);
DISPLAY INVISIBLE (-2255 3700);
FORCEPROP 2 LAST CDS_LIB mstr_discrete
J 0
(-2300 3600);
PAINT MONO (-2300 3600);
DISPLAY INVISIBLE (-2300 3600);
FORCEADD CAP..1
(-2300 3950);
FORCEPROP 1 LAST VALUE 3300PF
J 0
(-2175 4000);
DISPLAY 0.617021 (-2175 4000);
PAINT SKYBLUE (-2175 4000);
FORCEPROP 1 LAST TOLERANCE 10%
J 0
(-2175 3900);
DISPLAY 0.617021 (-2175 3900);
PAINT SKYBLUE (-2175 3900);
FORCEPROP 1 LAST LOCATION C7F3
J 0
(-2200 4050);
DISPLAY 0.617021 (-2200 4050);
PAINT AQUA (-2200 4050);
FORCEPROP 1 LASTPIN (-2300 4050) $PN 1
J 0
(-2290 4030);
DISPLAY 0.617021 (-2290 4030);
PAINT WHITE (-2290 4030);
FORCEPROP 1 LASTPIN (-2300 3850) $PN 2
J 0
(-2290 3830);
DISPLAY 0.617021 (-2290 3830);
PAINT WHITE (-2290 3830);
FORCEPROP 1 LAST VOLTAGE 50V
J 0
(-2175 3950);
DISPLAY 0.617021 (-2175 3950);
PAINT SKYBLUE (-2175 3950);
FORCEPROP 1 LAST MATERIAL EMPTY
J 0
(-2075 3925);
DISPLAY 0.617021 (-2075 3925);
PAINT RED (-2075 3925);
FORCEPROP 1 LAST PACK_TYPE 0402LF
J 0
(-2175 3850);
DISPLAY 0.617021 (-2175 3850);
PAINT SKYBLUE (-2175 3850);
FORCEPROP 1 LAST PART_NUMBER A36096-091
J 0
(-2175 3800);
DISPLAY 0.617021 (-2175 3800);
PAINT BLUE (-2175 3800);
FORCEPROP 2 LAST BOM_COST PVPP_KLM_VR
J 0
(-2250 4100);
DISPLAY 1.042553 (-2250 4100);
PAINT WHITE (-2250 4100);
DISPLAY INVISIBLE (-2250 4100);
FORCEPROP 2 LAST REUSE_ID 26
J 0
(-2250 4150);
DISPLAY 1.042553 (-2250 4150);
PAINT ORANGE (-2250 4150);
DISPLAY INVISIBLE (-2250 4150);
FORCEPROP 2 LAST CDS_SEC 1
J 0
(-2250 4150);
DISPLAY 1.042553 (-2250 4150);
PAINT ORANGE (-2250 4150);
DISPLAY INVISIBLE (-2250 4150);
FORCEPROP 2 LAST $SEC 1
J 0
(-2250 4150);
DISPLAY 0.680851 (-2250 4150);
PAINT MONO (-2250 4150);
DISPLAY INVISIBLE (-2250 4150);
FORCEPROP 1 LAST PATH I175
J 0
(-2250 4100);
DISPLAY 0.978723 (-2250 4100);
PAINT WHITE (-2250 4100);
DISPLAY INVISIBLE (-2250 4100);
FORCEPROP 2 LAST ROOM PVPP_KLM_VR
J 0
(-2250 4075);
PAINT GREEN (-2250 4075);
DISPLAY INVISIBLE (-2250 4075);
FORCEPROP 2 LAST CDS_LOCATION C7F3
J 0
(-2200 4050);
DISPLAY 0.617021 (-2200 4050);
PAINT AQUA (-2200 4050);
DISPLAY INVISIBLE (-2200 4050);
FORCEPROP 2 LAST CDS_LIB mstr_discrete
J 0
(-2300 3950);
PAINT MONO (-2300 3950);
DISPLAY INVISIBLE (-2300 3950);
FORCEADD GND..1
(-1725 3675);
FORCEPROP 3 LASTPIN (-1725 3725) SIG_NAME GND\g
J 0
(-1715 3735);
DISPLAY 0.659574 (-1715 3735);
PAINT MONO (-1715 3735);
DISPLAY INVISIBLE (-1715 3735);
FORCEPROP 1 LAST HDL_POWER GND
J 0
(-1725 3825);
DISPLAY 0.872340 (-1725 3825);
PAINT GREEN (-1725 3825);
DISPLAY INVISIBLE (-1725 3825);
FORCEPROP 1 LAST BODY_TYPE PLUMBING
J 0
(-1770 3632);
DISPLAY 0.340426 (-1770 3632);
PAINT GREEN (-1770 3632);
DISPLAY INVISIBLE (-1770 3632);
FORCEPROP 1 LAST PATH I176
J 0
(-1650 3675);
DISPLAY 0.872340 (-1650 3675);
PAINT AQUA (-1650 3675);
DISPLAY INVISIBLE (-1650 3675);
FORCEPROP 1 LAST SIZE 1B
J 0
(-1650 3625);
DISPLAY 0.872340 (-1650 3625);
PAINT GREEN (-1650 3625);
DISPLAY INVISIBLE (-1650 3625);
FORCEPROP 2 LAST CDS_LIB mstr_symbols
J 0
(-1725 3675);
PAINT MONO (-1725 3675);
DISPLAY INVISIBLE (-1725 3675);
FORCEPROP 1 LAST VOLTAGE 0
J 0
(-1725 3675);
PAINT SKYBLUE (-1725 3675);
DISPLAY INVISIBLE (-1725 3675);
FORCEPROP 2 LAST ROOM PVPP_KLM_VR
J 0
(-2300 3750);
DISPLAY 1.042553 (-2300 3750);
PAINT GREEN (-2300 3750);
DISPLAY INVISIBLE (-2300 3750);
FORCEPROP 2 LAST BOM_COST PVPP_KLM_VR
J 0
(-2575 3750);
DISPLAY 1.042553 (-2575 3750);
PAINT WHITE (-2575 3750);
DISPLAY INVISIBLE (-2575 3750);
FORCEADD RES..2
(-1725 3925);
FORCEPROP 1 LAST PART_NUMBER G22026-003
J 0
(-1685 3800);
DISPLAY 0.617021 (-1685 3800);
PAINT BLUE (-1685 3800);
FORCEPROP 1 LAST LOCATION R7F10
J 0
(-1680 4050);
DISPLAY 0.617021 (-1680 4050);
PAINT AQUA (-1680 4050);
FORCEPROP 1 LAST VALUE 120.0
J 0
(-1680 4000);
DISPLAY 0.617021 (-1680 4000);
PAINT SKYBLUE (-1680 4000);
FORCEPROP 1 LAST WATTAGE 1/10W
J 0
(-1685 3900);
DISPLAY 0.617021 (-1685 3900);
PAINT SKYBLUE (-1685 3900);
FORCEPROP 1 LAST MATERIAL CHIP
J 0
(-1685 3850);
DISPLAY 0.617021 (-1685 3850);
PAINT SKYBLUE (-1685 3850);
FORCEPROP 1 LAST TOLERANCE 1%
J 0
(-1680 3950);
DISPLAY 0.617021 (-1680 3950);
PAINT SKYBLUE (-1680 3950);
FORCEPROP 1 LASTPIN (-1725 4025) $PN 1
J 0
(-1720 3987);
DISPLAY 0.617021 (-1720 3987);
PAINT WHITE (-1720 3987);
FORCEPROP 1 LASTPIN (-1725 3825) $PN 2
J 0
(-1720 3835);
DISPLAY 0.617021 (-1720 3835);
PAINT WHITE (-1720 3835);
FORCEPROP 1 LAST PACK_TYPE 0603
J 0
(-1685 3750);
DISPLAY 0.617021 (-1685 3750);
PAINT SKYBLUE (-1685 3750);
FORCEPROP 2 LAST SEC_TYPE 0603
J 0
(-1675 4150);
DISPLAY 1.021277 (-1675 4150);
PAINT ORANGE (-1675 4150);
DISPLAY INVISIBLE (-1675 4150);
FORCEPROP 2 LAST BOM_COST PVPP_KLM_VR
J 0
(-1680 4105);
DISPLAY 1.042553 (-1680 4105);
PAINT WHITE (-1680 4105);
DISPLAY INVISIBLE (-1680 4105);
FORCEPROP 2 LAST REUSE_ID 34
J 0
(-1675 4150);
DISPLAY 1.042553 (-1675 4150);
PAINT ORANGE (-1675 4150);
DISPLAY INVISIBLE (-1675 4150);
FORCEPROP 2 LAST SEC 1
J 0
(-1675 4150);
DISPLAY 0.680851 (-1675 4150);
PAINT MONO (-1675 4150);
DISPLAY INVISIBLE (-1675 4150);
FORCEPROP 1 LAST PATH I177
J 0
(-1675 4100);
DISPLAY 0.978723 (-1675 4100);
PAINT WHITE (-1675 4100);
DISPLAY INVISIBLE (-1675 4100);
FORCEPROP 2 LAST ROOM PVPP_KLM_VR
J 0
(-1680 4080);
PAINT GREEN (-1680 4080);
DISPLAY INVISIBLE (-1680 4080);
FORCEPROP 2 LAST CDS_LOCATION R7F10
J 0
(-1680 4050);
DISPLAY 0.617021 (-1680 4050);
PAINT AQUA (-1680 4050);
DISPLAY INVISIBLE (-1680 4050);
FORCEPROP 2 LAST CDS_LIB mstr_discrete
J 0
(-1725 3925);
PAINT MONO (-1725 3925);
DISPLAY INVISIBLE (-1725 3925);
FORCEADD INDUCTOR..1
(-1950 4100);
FORCEPROP 1 LAST PART_NUMBER E13358-018
J 0
(-2050 4200);
DISPLAY 0.617021 (-2050 4200);
PAINT BLUE (-2050 4200);
FORCEPROP 1 LAST LOCATION L7F1
J 0
(-2000 4150);
DISPLAY 0.617021 (-2000 4150);
PAINT AQUA (-2000 4150);
FORCEPROP 1 LAST MATERIAL IND
J 0
(-1985 4040);
DISPLAY 0.617021 (-1985 4040);
PAINT SKYBLUE (-1985 4040);
FORCEPROP 1 LAST PACK_TYPE SM
J 0
(-1810 4115);
DISPLAY 0.617021 (-1810 4115);
PAINT SKYBLUE (-1810 4115);
FORCEPROP 1 LASTPIN (-1850 4100) $PN 2
J 2
(-1840 4110);
DISPLAY 0.617021 (-1840 4110);
PAINT WHITE (-1840 4110);
FORCEPROP 1 LASTPIN (-2050 4100) $PN 1
J 0
(-2050 4110);
DISPLAY 0.617021 (-2050 4110);
PAINT WHITE (-2050 4110);
FORCEPROP 1 LAST VALUE 0.47UH
J 2
(-2080 4115);
DISPLAY 0.617021 (-2080 4115);
PAINT SKYBLUE (-2080 4115);
FORCEPROP 2 LAST ROOM PVPP_KLM_VR
J 2
(-1950 4100);
PAINT GREEN (-1950 4100);
DISPLAY INVISIBLE (-1950 4100);
FORCEPROP 2 LAST CDS_LOCATION L7F1
J 0
(-2000 4150);
DISPLAY 0.617021 (-2000 4150);
PAINT AQUA (-2000 4150);
DISPLAY INVISIBLE (-2000 4150);
FORCEPROP 2 LAST BOM_COST PVPP_KLM_VR
J 0
(-1950 4100);
PAINT WHITE (-1950 4100);
DISPLAY INVISIBLE (-1950 4100);
FORCEPROP 2 LAST CDS_LIB mstr_discrete
J 0
(-1950 4100);
PAINT MONO (-1950 4100);
DISPLAY INVISIBLE (-1950 4100);
FORCEPROP 2 LAST REUSE_ID 30
J 0
(-2050 4300);
DISPLAY 1.042553 (-2050 4300);
PAINT ORANGE (-2050 4300);
DISPLAY INVISIBLE (-2050 4300);
FORCEPROP 2 LAST CDS_SEC 1
J 0
(-2050 4300);
DISPLAY 1.042553 (-2050 4300);
PAINT ORANGE (-2050 4300);
DISPLAY INVISIBLE (-2050 4300);
FORCEPROP 2 LAST $SEC 1
J 0
(-2050 4300);
DISPLAY 0.680851 (-2050 4300);
PAINT MONO (-2050 4300);
DISPLAY INVISIBLE (-2050 4300);
FORCEPROP 0 LAST TOLERANCE 1%
J 0
(-2050 4250);
PAINT SKYBLUE (-2050 4250);
DISPLAY INVISIBLE (-2050 4250);
FORCEPROP 1 LAST PATH I178
J 0
(-2050 4250);
DISPLAY 0.978723 (-2050 4250);
PAINT ORANGE (-2050 4250);
DISPLAY INVISIBLE (-2050 4250);
FORCEADD GND..1
(-1400 3525);
FORCEPROP 3 LASTPIN (-1400 3575) SIG_NAME GND\g
J 0
(-1390 3585);
DISPLAY 0.659574 (-1390 3585);
PAINT MONO (-1390 3585);
DISPLAY INVISIBLE (-1390 3585);
FORCEPROP 1 LAST HDL_POWER GND
J 0
(-1400 3675);
DISPLAY 0.872340 (-1400 3675);
PAINT GREEN (-1400 3675);
DISPLAY INVISIBLE (-1400 3675);
FORCEPROP 1 LAST BODY_TYPE PLUMBING
J 0
(-1445 3482);
DISPLAY 0.340426 (-1445 3482);
PAINT GREEN (-1445 3482);
DISPLAY INVISIBLE (-1445 3482);
FORCEPROP 1 LAST VOLTAGE 0
J 0
(-1400 3525);
PAINT SKYBLUE (-1400 3525);
DISPLAY INVISIBLE (-1400 3525);
FORCEPROP 2 LAST CDS_LIB mstr_symbols
J 0
(-1400 3525);
PAINT MONO (-1400 3525);
DISPLAY INVISIBLE (-1400 3525);
FORCEPROP 1 LAST PATH I179
J 0
(-1325 3525);
DISPLAY 0.872340 (-1325 3525);
PAINT AQUA (-1325 3525);
DISPLAY INVISIBLE (-1325 3525);
FORCEPROP 1 LAST SIZE 1B
J 0
(-1325 3475);
DISPLAY 0.872340 (-1325 3475);
PAINT GREEN (-1325 3475);
DISPLAY INVISIBLE (-1325 3475);
FORCEPROP 2 LAST ROOM PVPP_KLM_VR
J 0
(-1975 3600);
DISPLAY 1.042553 (-1975 3600);
PAINT GREEN (-1975 3600);
DISPLAY INVISIBLE (-1975 3600);
FORCEPROP 2 LAST BOM_COST PVPP_KLM_VR
J 0
(-2250 3600);
DISPLAY 1.042553 (-2250 3600);
PAINT WHITE (-2250 3600);
DISPLAY INVISIBLE (-2250 3600);
FORCEADD CAPP..1
(-1400 3900);
FORCEPROP 1 LAST PART_NUMBER 724613-042
J 0
(-1350 3750);
DISPLAY 0.617021 (-1350 3750);
PAINT BLUE (-1350 3750);
FORCEPROP 1 LAST VOLTAGE 6.3V
J 0
(-1350 3900);
DISPLAY 0.617021 (-1350 3900);
PAINT SKYBLUE (-1350 3900);
FORCEPROP 1 LAST TOLERANCE 20%
J 0
(-1350 3950);
DISPLAY 0.617021 (-1350 3950);
PAINT SKYBLUE (-1350 3950);
FORCEPROP 1 LASTPIN (-1400 4000) $PN 1
J 0
(-1390 3985);
DISPLAY 0.617021 (-1390 3985);
PAINT WHITE (-1390 3985);
FORCEPROP 1 LASTPIN (-1400 3800) $PN 2
J 0
(-1390 3785);
DISPLAY 0.617021 (-1390 3785);
PAINT WHITE (-1390 3785);
FORCEPROP 1 LAST VALUE 330UF
J 0
(-1350 4000);
DISPLAY 0.617021 (-1350 4000);
PAINT SKYBLUE (-1350 4000);
FORCEPROP 1 LAST LOCATION C6F4
J 0
(-1350 4050);
DISPLAY 0.617021 (-1350 4050);
PAINT AQUA (-1350 4050);
FORCEPROP 0 LAST GROUP PWR_BULK_CAP
J 0
(-1360 3701);
DISPLAY 0.638298 (-1360 3701);
PAINT BROWN (-1360 3701);
DISPLAY BOTH (-1360 3701);
FORCEPROP 1 LAST PACK_TYPE 7343LF
J 0
(-1350 3800);
DISPLAY 0.617021 (-1350 3800);
PAINT SKYBLUE (-1350 3800);
FORCEPROP 1 LAST MATERIAL POSCAP
J 0
(-1350 3850);
DISPLAY 0.617021 (-1350 3850);
PAINT SKYBLUE (-1350 3850);
FORCEPROP 2 LAST REUSE_ID 28
J 0
(-1350 4100);
DISPLAY 1.042553 (-1350 4100);
PAINT ORANGE (-1350 4100);
DISPLAY INVISIBLE (-1350 4100);
FORCEPROP 2 LAST CDS_SEC 1
J 0
(-1350 4100);
DISPLAY 1.042553 (-1350 4100);
PAINT ORANGE (-1350 4100);
DISPLAY INVISIBLE (-1350 4100);
FORCEPROP 2 LAST $SEC 1
J 0
(-1350 4100);
DISPLAY 0.680851 (-1350 4100);
PAINT MONO (-1350 4100);
DISPLAY INVISIBLE (-1350 4100);
FORCEPROP 1 LAST PATH I180
J 0
(-1350 4050);
DISPLAY 0.978723 (-1350 4050);
PAINT ORANGE (-1350 4050);
DISPLAY INVISIBLE (-1350 4050);
FORCEPROP 2 LAST CDS_LOCATION C6F4
J 0
(-1350 4000);
DISPLAY 0.617021 (-1350 4000);
PAINT AQUA (-1350 4000);
DISPLAY INVISIBLE (-1350 4000);
FORCEPROP 2 LAST ROOM PVPP_KLM_VR
J 0
(-1400 3900);
PAINT GREEN (-1400 3900);
DISPLAY INVISIBLE (-1400 3900);
FORCEPROP 2 LAST BOM_COST PVPP_KLM_VR
J 0
(-1400 3900);
DISPLAY 0.659574 (-1400 3900);
PAINT WHITE (-1400 3900);
DISPLAY INVISIBLE (-1400 3900);
FORCEPROP 2 LAST CDS_LIB mstr_discrete
J 0
(-1400 3900);
PAINT MONO (-1400 3900);
DISPLAY INVISIBLE (-1400 3900);
FORCEADD GND..1
(-775 3525);
FORCEPROP 3 LASTPIN (-775 3575) SIG_NAME GND\g
J 0
(-765 3585);
DISPLAY 0.659574 (-765 3585);
PAINT MONO (-765 3585);
DISPLAY INVISIBLE (-765 3585);
FORCEPROP 1 LAST SIZE 1B
J 0
(-700 3475);
DISPLAY 0.872340 (-700 3475);
PAINT GREEN (-700 3475);
DISPLAY INVISIBLE (-700 3475);
FORCEPROP 1 LAST PATH I183
J 0
(-700 3525);
DISPLAY 0.872340 (-700 3525);
PAINT AQUA (-700 3525);
DISPLAY INVISIBLE (-700 3525);
FORCEPROP 1 LAST VOLTAGE 0
J 0
(-775 3525);
PAINT SKYBLUE (-775 3525);
DISPLAY INVISIBLE (-775 3525);
FORCEPROP 2 LAST CDS_LIB mstr_symbols
J 0
(-775 3525);
PAINT MONO (-775 3525);
DISPLAY INVISIBLE (-775 3525);
FORCEPROP 2 LAST ROOM PVPP_KLM_VR
J 0
(-1350 3600);
DISPLAY 1.042553 (-1350 3600);
PAINT GREEN (-1350 3600);
DISPLAY INVISIBLE (-1350 3600);
FORCEPROP 2 LAST BOM_COST PVPP_KLM_VR
J 0
(-1625 3600);
DISPLAY 1.042553 (-1625 3600);
PAINT WHITE (-1625 3600);
DISPLAY INVISIBLE (-1625 3600);
FORCEPROP 1 LAST BODY_TYPE PLUMBING
J 0
(-820 3482);
DISPLAY 0.340426 (-820 3482);
PAINT GREEN (-820 3482);
DISPLAY INVISIBLE (-820 3482);
FORCEPROP 1 LAST HDL_POWER GND
J 0
(-775 3675);
DISPLAY 0.872340 (-775 3675);
PAINT GREEN (-775 3675);
DISPLAY INVISIBLE (-775 3675);
FORCEADD CAP..1
(-775 3900);
FORCEPROP 1 LAST MATERIAL X6S
J 0
(-725 3800);
DISPLAY 0.617021 (-725 3800);
PAINT SKYBLUE (-725 3800);
FORCEPROP 1 LAST TOLERANCE 20%
J 0
(-725 3850);
DISPLAY 0.617021 (-725 3850);
PAINT SKYBLUE (-725 3850);
FORCEPROP 1 LASTPIN (-775 4000) $PN 1
J 0
(-765 3980);
DISPLAY 0.617021 (-765 3980);
PAINT WHITE (-765 3980);
FORCEPROP 1 LAST VOLTAGE 4V
J 0
(-725 3900);
DISPLAY 0.617021 (-725 3900);
PAINT SKYBLUE (-725 3900);
FORCEPROP 1 LAST LOCATION C3T7
J 0
(-725 4000);
DISPLAY 0.617021 (-725 4000);
PAINT AQUA (-725 4000);
FORCEPROP 1 LASTPIN (-775 3800) $PN 2
J 0
(-765 3780);
DISPLAY 0.617021 (-765 3780);
PAINT WHITE (-765 3780);
FORCEPROP 1 LAST VALUE 47UF
J 0
(-725 3950);
DISPLAY 0.617021 (-725 3950);
PAINT SKYBLUE (-725 3950);
FORCEPROP 1 LAST PART_NUMBER C95333-006
J 0
(-725 3750);
DISPLAY 0.617021 (-725 3750);
PAINT BLUE (-725 3750);
FORCEPROP 1 LAST PACK_TYPE 0805
J 0
(-725 3700);
DISPLAY 0.617021 (-725 3700);
PAINT SKYBLUE (-725 3700);
FORCEPROP 0 LAST GROUP PWR_MLCC_CAP
J 0
(-719 3612);
DISPLAY 0.638298 (-719 3612);
PAINT BROWN (-719 3612);
DISPLAY BOTH (-719 3612);
FORCEPROP 2 LAST ROOM PVPP_KLM_VR
J 0
(-775 3900);
PAINT GREEN (-775 3900);
DISPLAY INVISIBLE (-775 3900);
FORCEPROP 2 LAST BOM_COST PVPP_KLM_VR
J 0
(-775 3900);
PAINT WHITE (-775 3900);
DISPLAY INVISIBLE (-775 3900);
FORCEPROP 2 LAST CDS_LIB mstr_discrete
J 0
(-775 3900);
PAINT MONO (-775 3900);
DISPLAY INVISIBLE (-775 3900);
FORCEPROP 2 LAST CDS_LOCATION C3T7
J 0
(-725 4000);
DISPLAY 0.617021 (-725 4000);
PAINT AQUA (-725 4000);
DISPLAY INVISIBLE (-725 4000);
FORCEPROP 1 LAST PATH I184
J 0
(-725 4050);
DISPLAY 0.978723 (-725 4050);
PAINT WHITE (-725 4050);
DISPLAY INVISIBLE (-725 4050);
FORCEPROP 2 LAST REUSE_ID 33
J 0
(-725 4100);
DISPLAY 1.042553 (-725 4100);
PAINT ORANGE (-725 4100);
DISPLAY INVISIBLE (-725 4100);
FORCEPROP 2 LAST CDS_SEC 1
J 0
(-725 4100);
DISPLAY 1.042553 (-725 4100);
PAINT ORANGE (-725 4100);
DISPLAY INVISIBLE (-725 4100);
FORCEPROP 2 LAST $SEC 1
J 0
(-725 4100);
DISPLAY 0.680851 (-725 4100);
PAINT MONO (-725 4100);
DISPLAY INVISIBLE (-725 4100);
FORCEADD GND..1
(-475 3525);
FORCEPROP 3 LASTPIN (-475 3575) SIG_NAME GND\g
J 0
(-465 3585);
DISPLAY 0.659574 (-465 3585);
PAINT MONO (-465 3585);
DISPLAY INVISIBLE (-465 3585);
FORCEPROP 1 LAST SIZE 1B
J 0
(-400 3475);
DISPLAY 0.872340 (-400 3475);
PAINT GREEN (-400 3475);
DISPLAY INVISIBLE (-400 3475);
FORCEPROP 1 LAST PATH I185
J 0
(-400 3525);
DISPLAY 0.872340 (-400 3525);
PAINT AQUA (-400 3525);
DISPLAY INVISIBLE (-400 3525);
FORCEPROP 2 LAST CDS_LIB mstr_symbols
J 0
(-475 3525);
PAINT MONO (-475 3525);
DISPLAY INVISIBLE (-475 3525);
FORCEPROP 1 LAST VOLTAGE 0
J 0
(-475 3525);
PAINT SKYBLUE (-475 3525);
DISPLAY INVISIBLE (-475 3525);
FORCEPROP 2 LAST ROOM PVPP_KLM_VR
J 0
(-1050 3600);
DISPLAY 1.042553 (-1050 3600);
PAINT GREEN (-1050 3600);
DISPLAY INVISIBLE (-1050 3600);
FORCEPROP 2 LAST BOM_COST PVPP_KLM_VR
J 0
(-1325 3600);
DISPLAY 1.042553 (-1325 3600);
PAINT WHITE (-1325 3600);
DISPLAY INVISIBLE (-1325 3600);
FORCEPROP 1 LAST BODY_TYPE PLUMBING
J 0
(-520 3482);
DISPLAY 0.340426 (-520 3482);
PAINT GREEN (-520 3482);
DISPLAY INVISIBLE (-520 3482);
FORCEPROP 1 LAST HDL_POWER GND
J 0
(-475 3675);
DISPLAY 0.872340 (-475 3675);
PAINT GREEN (-475 3675);
DISPLAY INVISIBLE (-475 3675);
FORCEADD CAP..1
(-475 3925);
FORCEPROP 1 LASTPIN (-475 4025) $PN 1
J 0
(-465 4005);
DISPLAY 0.617021 (-465 4005);
PAINT WHITE (-465 4005);
FORCEPROP 1 LAST LOCATION C3T9
J 0
(-425 4025);
DISPLAY 0.617021 (-425 4025);
PAINT AQUA (-425 4025);
FORCEPROP 1 LAST PART_NUMBER C95333-006
J 0
(-425 3775);
DISPLAY 0.617021 (-425 3775);
PAINT BLUE (-425 3775);
FORCEPROP 1 LAST VALUE 47UF
J 0
(-425 3975);
DISPLAY 0.617021 (-425 3975);
PAINT SKYBLUE (-425 3975);
FORCEPROP 1 LAST TOLERANCE 20%
J 0
(-425 3875);
DISPLAY 0.617021 (-425 3875);
PAINT SKYBLUE (-425 3875);
FORCEPROP 1 LAST PACK_TYPE 0805
J 0
(-425 3725);
DISPLAY 0.617021 (-425 3725);
PAINT SKYBLUE (-425 3725);
FORCEPROP 1 LAST VOLTAGE 4V
J 0
(-425 3925);
DISPLAY 0.617021 (-425 3925);
PAINT SKYBLUE (-425 3925);
FORCEPROP 1 LAST MATERIAL X6S
J 0
(-425 3825);
DISPLAY 0.617021 (-425 3825);
PAINT SKYBLUE (-425 3825);
FORCEPROP 1 LASTPIN (-475 3825) $PN 2
J 0
(-465 3805);
DISPLAY 0.617021 (-465 3805);
PAINT WHITE (-465 3805);
FORCEPROP 0 LAST GROUP PWR_MLCC_CAP
J 0
(-419 3662);
DISPLAY 0.638298 (-419 3662);
PAINT BROWN (-419 3662);
DISPLAY BOTH (-419 3662);
FORCEPROP 2 LAST $SEC 1
J 0
(-425 4125);
DISPLAY 0.680851 (-425 4125);
PAINT MONO (-425 4125);
DISPLAY INVISIBLE (-425 4125);
FORCEPROP 2 LAST CDS_SEC 1
J 0
(-425 4125);
DISPLAY 1.042553 (-425 4125);
PAINT ORANGE (-425 4125);
DISPLAY INVISIBLE (-425 4125);
FORCEPROP 2 LAST REUSE_ID 33
J 0
(-425 4125);
DISPLAY 1.042553 (-425 4125);
PAINT ORANGE (-425 4125);
DISPLAY INVISIBLE (-425 4125);
FORCEPROP 1 LAST PATH I186
J 0
(-425 4075);
DISPLAY 0.978723 (-425 4075);
PAINT WHITE (-425 4075);
DISPLAY INVISIBLE (-425 4075);
FORCEPROP 2 LAST CDS_LOCATION C3T9
J 0
(-425 4025);
DISPLAY 0.617021 (-425 4025);
PAINT AQUA (-425 4025);
DISPLAY INVISIBLE (-425 4025);
FORCEPROP 2 LAST ROOM PVPP_KLM_VR
J 0
(-475 3925);
PAINT GREEN (-475 3925);
DISPLAY INVISIBLE (-475 3925);
FORCEPROP 2 LAST CDS_LIB mstr_discrete
J 0
(-475 3925);
PAINT MONO (-475 3925);
DISPLAY INVISIBLE (-475 3925);
FORCEPROP 2 LAST BOM_COST PVPP_KLM_VR
J 0
(-475 3925);
PAINT WHITE (-475 3925);
DISPLAY INVISIBLE (-475 3925);
FORCEADD PVPP_ABC..1
(-400 4200);
FORCEPROP 3 LASTPIN (-400 4150) SIG_NAME PVPP_ABC\g
J 0
(-390 4160);
DISPLAY 0.659574 (-390 4160);
PAINT MONO (-390 4160);
DISPLAY INVISIBLE (-390 4160);
FORCEPROP 1 LAST HDL_POWER PVPP_ABC
J 1
(-400 4250);
DISPLAY 0.872340 (-400 4250);
PAINT GREEN (-400 4250);
DISPLAY INVISIBLE (-400 4250);
FORCEPROP 1 LAST BODY_TYPE PLUMBING
J 0
(-445 4157);
DISPLAY 0.340426 (-445 4157);
PAINT GREEN (-445 4157);
DISPLAY INVISIBLE (-445 4157);
FORCEPROP 1 LAST VOLTAGE 2.5V
J 0
(-445 4157);
DISPLAY 0.340426 (-445 4157);
PAINT SKYBLUE (-445 4157);
DISPLAY INVISIBLE (-445 4157);
FORCEPROP 2 LAST CDS_LIB mstr_symbols
J 0
(-400 4200);
PAINT ORANGE (-400 4200);
DISPLAY INVISIBLE (-400 4200);
FORCEPROP 1 LAST PATH I187
J 0
(-350 4225);
DISPLAY 0.872340 (-350 4225);
PAINT AQUA (-350 4225);
DISPLAY INVISIBLE (-350 4225);
FORCEPROP 2 LAST BOM_COST PVPP_KLM_VR
J 0
(-325 4300);
PAINT MONO (-325 4300);
DISPLAY INVISIBLE (-325 4300);
FORCEPROP 2 LAST ROOM PVPP_KLM_VR
J 0
(-150 4300);
PAINT ORANGE (-150 4300);
DISPLAY INVISIBLE (-150 4300);
FORCEADD OFFPAGE..2
(-2400 1225);
FORCEPROP 2 LAST $XR1 190 
J 0
(-2121 1225);
DISPLAY 0.638298 (-2121 1225);
PAINT MONO (-2121 1225);
FORCEPROP 2 LAST $XR0 91 
J 0
(-2211 1225);
DISPLAY 0.638298 (-2211 1225);
PAINT MONO (-2211 1225);
FORCEPROP 1 LAST COMMENT_BODY TRUE
J 0
(-2445 1130);
DISPLAY 0.872340 (-2445 1130);
PAINT PEACH (-2445 1130);
DISPLAY INVISIBLE (-2445 1130);
FORCEPROP 1 LAST OFFPAGE TRUE
J 0
(-2075 1100);
PAINT GREEN (-2075 1100);
DISPLAY INVISIBLE (-2075 1100);
FORCEPROP 2 LAST PATH I188
J 0
(-2200 1275);
DISPLAY 1.021277 (-2200 1275);
PAINT ORANGE (-2200 1275);
DISPLAY INVISIBLE (-2200 1275);
FORCEPROP 0 LAST TOLERANCE 1%
J 0
(-2225 1300);
PAINT SKYBLUE (-2225 1300);
DISPLAY INVISIBLE (-2225 1300);
FORCEPROP 2 LAST CDS_LIB mstr_standard
J 2
(-2400 1225);
PAINT MONO (-2400 1225);
DISPLAY INVISIBLE (-2400 1225);
FORCEPROP 2 LAST ROOM PVPP_KLM_VR
J 0
(-2825 1300);
DISPLAY 1.042553 (-2825 1300);
PAINT GREEN (-2825 1300);
DISPLAY INVISIBLE (-2825 1300);
FORCEPROP 2 LAST BOM_COST PVPP_KLM_VR
J 0
(-3100 1300);
DISPLAY 1.042553 (-3100 1300);
PAINT WHITE (-3100 1300);
DISPLAY INVISIBLE (-3100 1300);
FORCEADD AGND_SCSI..1
(-4025 2100);
FORCEPROP 3 LASTPIN (-4025 2150) SIG_NAME AGND_PVPP_ABC\g
J 0
(-4015 2160);
DISPLAY 0.659574 (-4015 2160);
PAINT MONO (-4015 2160);
DISPLAY INVISIBLE (-4015 2160);
FORCEPROP 1 LAST HDL_POWER AGND_PVPP_ABC
J 1
(-4000 2025);
DISPLAY 0.617021 (-4000 2025);
PAINT GREEN (-4000 2025);
FORCEPROP 1 LAST BODY_TYPE PLUMBING
J 0
(-4070 2057);
DISPLAY 0.340426 (-4070 2057);
PAINT GREEN (-4070 2057);
DISPLAY INVISIBLE (-4070 2057);
FORCEPROP 1 LAST PATH I189
J 0
(-3950 2100);
DISPLAY 0.872340 (-3950 2100);
PAINT AQUA (-3950 2100);
DISPLAY INVISIBLE (-3950 2100);
FORCEPROP 2 LAST CDS_LIB mstr_symbols
J 0
(-4025 2100);
PAINT MONO (-4025 2100);
DISPLAY INVISIBLE (-4025 2100);
FORCEPROP 1 LAST VOLTAGE 0.0V
J 0
(-4070 2057);
DISPLAY 0.340426 (-4070 2057);
PAINT SKYBLUE (-4070 2057);
DISPLAY INVISIBLE (-4070 2057);
FORCEPROP 2 LAST BOM_COST PVPP_KLM_VR
J 0
(-4175 2050);
DISPLAY 1.042553 (-4175 2050);
PAINT WHITE (-4175 2050);
DISPLAY INVISIBLE (-4175 2050);
FORCEPROP 2 LAST ROOM PVPP_KLM_VR
J 0
(-4175 2050);
DISPLAY 1.042553 (-4175 2050);
PAINT GREEN (-4175 2050);
DISPLAY INVISIBLE (-4175 2050);
FORCEADD AGND_SCSI..1
(-4400 1600);
FORCEPROP 3 LASTPIN (-4400 1650) SIG_NAME AGND_PVPP_ABC\g
J 0
(-4390 1660);
DISPLAY 0.659574 (-4390 1660);
PAINT MONO (-4390 1660);
DISPLAY INVISIBLE (-4390 1660);
FORCEPROP 1 LAST HDL_POWER AGND_PVPP_ABC
J 1
(-4375 1525);
DISPLAY 0.617021 (-4375 1525);
PAINT GREEN (-4375 1525);
FORCEPROP 1 LAST BODY_TYPE PLUMBING
J 0
(-4445 1557);
DISPLAY 0.340426 (-4445 1557);
PAINT GREEN (-4445 1557);
DISPLAY INVISIBLE (-4445 1557);
FORCEPROP 1 LAST PATH I190
J 0
(-4325 1600);
DISPLAY 0.872340 (-4325 1600);
PAINT AQUA (-4325 1600);
DISPLAY INVISIBLE (-4325 1600);
FORCEPROP 1 LAST VOLTAGE 0
J 0
(-4375 1625);
DISPLAY 1.021277 (-4375 1625);
PAINT SKYBLUE (-4375 1625);
DISPLAY INVISIBLE (-4375 1625);
FORCEPROP 2 LAST CDS_LIB mstr_symbols
J 0
(-4400 1600);
PAINT MONO (-4400 1600);
DISPLAY INVISIBLE (-4400 1600);
FORCEADD P3V3_STBY..1
(-3875 1775);
FORCEPROP 3 LASTPIN (-3875 1725) SIG_NAME P3V3_STBY\g
J 0
(-3865 1735);
DISPLAY 0.659574 (-3865 1735);
PAINT MONO (-3865 1735);
DISPLAY INVISIBLE (-3865 1735);
FORCEPROP 1 LAST HDL_POWER P3V3_STBY
J 0
(-4175 1650);
DISPLAY 0.872340 (-4175 1650);
PAINT ORANGE (-4175 1650);
DISPLAY INVISIBLE (-4175 1650);
FORCEPROP 1 LAST BODY_TYPE PLUMBING
J 0
(-3920 1732);
DISPLAY 0.340426 (-3920 1732);
PAINT GREEN (-3920 1732);
DISPLAY INVISIBLE (-3920 1732);
FORCEPROP 1 LAST PATH I192
J 0
(-3830 1777);
DISPLAY 0.340426 (-3830 1777);
PAINT GREEN (-3830 1777);
DISPLAY INVISIBLE (-3830 1777);
FORCEPROP 1 LAST SIZE 1B
J 0
(-3830 1797);
DISPLAY 0.340426 (-3830 1797);
PAINT GREEN (-3830 1797);
DISPLAY INVISIBLE (-3830 1797);
FORCEPROP 1 LAST VOLTAGE +3.3V
J 0
(-3675 1925);
DISPLAY 1.021277 (-3675 1925);
PAINT SKYBLUE (-3675 1925);
DISPLAY INVISIBLE (-3675 1925);
FORCEPROP 2 LAST CDS_LIB mstr_symbols
J 0
(-3875 1775);
PAINT MONO (-3875 1775);
DISPLAY INVISIBLE (-3875 1775);
FORCEADD NCP3232L..1
(-3450 3125);
FORCEPROP 1 LAST PART_NUMBER H86355-001
J 0
(-3900 2125);
DISPLAY 0.617021 (-3900 2125);
PAINT BLUE (-3900 2125);
FORCEPROP 2 LASTPIN (-2950 3825) $PN 36
J 0
(-2940 3835);
DISPLAY 0.617021 (-2940 3835);
PAINT ORANGE (-2940 3835);
FORCEPROP 2 LASTPIN (-2950 3275) $PN 35
J 0
(-2940 3285);
DISPLAY 0.617021 (-2940 3285);
PAINT ORANGE (-2940 3285);
FORCEPROP 2 LASTPIN (-3950 3475) $PN 10
J 2
(-3960 3485);
DISPLAY 0.617021 (-3960 3485);
PAINT ORANGE (-3960 3485);
FORCEPROP 2 LASTPIN (-3950 3575) $PN 12
J 2
(-3960 3585);
DISPLAY 0.617021 (-3960 3585);
PAINT ORANGE (-3960 3585);
FORCEPROP 2 LASTPIN (-3950 3425) $PN 9
J 2
(-3960 3435);
DISPLAY 0.617021 (-3960 3435);
PAINT ORANGE (-3960 3435);
FORCEPROP 2 LASTPIN (-3950 3175) $PN 6
J 2
(-3960 3185);
DISPLAY 0.617021 (-3960 3185);
PAINT ORANGE (-3960 3185);
FORCEPROP 2 LASTPIN (-3950 3625) $PN 13
J 2
(-3960 3635);
DISPLAY 0.617021 (-3960 3635);
PAINT ORANGE (-3960 3635);
FORCEPROP 2 LASTPIN (-2950 3575) $PN 32
J 0
(-2940 3585);
DISPLAY 0.617021 (-2940 3585);
PAINT ORANGE (-2940 3585);
FORCEPROP 2 LASTPIN (-2950 3725) $PN 43
J 0
(-2940 3735);
DISPLAY 0.617021 (-2940 3735);
PAINT ORANGE (-2940 3735);
FORCEPROP 2 LASTPIN (-2950 3675) $PN 34
J 0
(-2940 3685);
DISPLAY 0.617021 (-2940 3685);
PAINT ORANGE (-2940 3685);
FORCEPROP 2 LASTPIN (-2950 3625) $PN 33
J 0
(-2940 3635);
DISPLAY 0.617021 (-2940 3635);
PAINT ORANGE (-2940 3635);
FORCEPROP 2 LASTPIN (-2950 3375) $PN 15
J 0
(-2940 3385);
DISPLAY 0.617021 (-2940 3385);
PAINT ORANGE (-2940 3385);
FORCEPROP 2 LASTPIN (-2950 3425) $PN 29
J 0
(-2940 3435);
DISPLAY 0.617021 (-2940 3435);
PAINT ORANGE (-2940 3435);
FORCEPROP 2 LASTPIN (-2950 3475) $PN 30
J 0
(-2940 3485);
DISPLAY 0.617021 (-2940 3485);
PAINT ORANGE (-2940 3485);
FORCEPROP 2 LASTPIN (-2950 3525) $PN 31
J 0
(-2940 3535);
DISPLAY 0.617021 (-2940 3535);
PAINT ORANGE (-2940 3535);
FORCEPROP 2 LASTPIN (-2950 3175) $PN 2
J 0
(-2940 3185);
DISPLAY 0.617021 (-2940 3185);
PAINT ORANGE (-2940 3185);
FORCEPROP 2 LASTPIN (-2950 3075) $PN 3
J 0
(-2940 3085);
DISPLAY 0.617021 (-2940 3085);
PAINT ORANGE (-2940 3085);
FORCEPROP 2 LASTPIN (-2950 2975) $PN 37
J 0
(-2940 2985);
DISPLAY 0.617021 (-2940 2985);
PAINT ORANGE (-2940 2985);
FORCEPROP 2 LASTPIN (-2950 2925) $PN 28
J 0
(-2940 2935);
DISPLAY 0.617021 (-2940 2935);
PAINT ORANGE (-2940 2935);
FORCEPROP 2 LASTPIN (-2950 2875) $PN 27
J 0
(-2940 2885);
DISPLAY 0.617021 (-2940 2885);
PAINT ORANGE (-2940 2885);
FORCEPROP 2 LASTPIN (-2950 2825) $PN 26
J 0
(-2940 2835);
DISPLAY 0.617021 (-2940 2835);
PAINT ORANGE (-2940 2835);
FORCEPROP 2 LASTPIN (-2950 2575) $PN 21
J 0
(-2940 2585);
DISPLAY 0.617021 (-2940 2585);
PAINT ORANGE (-2940 2585);
FORCEPROP 2 LASTPIN (-2950 2625) $PN 22
J 0
(-2940 2635);
DISPLAY 0.617021 (-2940 2635);
PAINT ORANGE (-2940 2635);
FORCEPROP 2 LASTPIN (-2950 2675) $PN 23
J 0
(-2940 2685);
DISPLAY 0.617021 (-2940 2685);
PAINT ORANGE (-2940 2685);
FORCEPROP 2 LASTPIN (-2950 2725) $PN 24
J 0
(-2940 2735);
DISPLAY 0.617021 (-2940 2735);
PAINT ORANGE (-2940 2735);
FORCEPROP 2 LASTPIN (-2950 2775) $PN 25
J 0
(-2940 2785);
DISPLAY 0.617021 (-2940 2785);
PAINT ORANGE (-2940 2785);
FORCEPROP 2 LASTPIN (-2950 2525) $PN 20
J 0
(-2940 2535);
DISPLAY 0.617021 (-2940 2535);
PAINT ORANGE (-2940 2535);
FORCEPROP 2 LASTPIN (-2950 2475) $PN 19
J 0
(-2940 2485);
DISPLAY 0.617021 (-2940 2485);
PAINT ORANGE (-2940 2485);
FORCEPROP 2 LASTPIN (-2950 2425) $PN 18
J 0
(-2940 2435);
DISPLAY 0.617021 (-2940 2435);
PAINT ORANGE (-2940 2435);
FORCEPROP 2 LASTPIN (-2950 2375) $PN 17
J 0
(-2940 2385);
DISPLAY 0.617021 (-2940 2385);
PAINT ORANGE (-2940 2385);
FORCEPROP 2 LASTPIN (-2950 2275) $PN 41
J 0
(-2940 2285);
DISPLAY 0.617021 (-2940 2285);
PAINT ORANGE (-2940 2285);
FORCEPROP 2 LASTPIN (-3950 3825) $PN 39
J 2
(-3960 3835);
DISPLAY 0.617021 (-3960 3835);
PAINT ORANGE (-3960 3835);
FORCEPROP 2 LASTPIN (-3950 3725) $PN 42
J 2
(-3960 3735);
DISPLAY 0.617021 (-3960 3735);
PAINT ORANGE (-3960 3735);
FORCEPROP 2 LASTPIN (-3950 3675) $PN 14
J 2
(-3960 3685);
DISPLAY 0.617021 (-3960 3685);
PAINT ORANGE (-3960 3685);
FORCEPROP 2 LASTPIN (-3950 3375) $PN 8
J 2
(-3960 3385);
DISPLAY 0.617021 (-3960 3385);
PAINT ORANGE (-3960 3385);
FORCEPROP 2 LASTPIN (-3950 3525) $PN 11
J 2
(-3960 3535);
DISPLAY 0.617021 (-3960 3535);
PAINT ORANGE (-3960 3535);
FORCEPROP 2 LASTPIN (-3950 3275) $PN 38
J 2
(-3960 3285);
DISPLAY 0.617021 (-3960 3285);
PAINT ORANGE (-3960 3285);
FORCEPROP 2 LASTPIN (-3950 3075) $PN 40
J 2
(-3960 3085);
DISPLAY 0.617021 (-3960 3085);
PAINT ORANGE (-3960 3085);
FORCEPROP 2 LASTPIN (-3950 2975) $PN 1
J 2
(-3960 2985);
DISPLAY 0.617021 (-3960 2985);
PAINT ORANGE (-3960 2985);
FORCEPROP 2 LASTPIN (-3950 2775) $PN 7
J 2
(-3960 2785);
DISPLAY 0.617021 (-3960 2785);
PAINT ORANGE (-3960 2785);
FORCEPROP 2 LASTPIN (-3950 2875) $PN 4
J 2
(-3960 2885);
DISPLAY 0.617021 (-3960 2885);
PAINT ORANGE (-3960 2885);
FORCEPROP 1 LAST MATERIAL IC
J 0
(-3900 4025);
DISPLAY 0.617021 (-3900 4025);
PAINT SKYBLUE (-3900 4025);
FORCEPROP 1 LAST LOCATION EU7F1
J 0
(-3900 4075);
DISPLAY 0.617021 (-3900 4075);
PAINT AQUA (-3900 4075);
FORCEPROP 2 LASTPIN (-2950 2325) $PN 16
J 0
(-2940 2335);
DISPLAY 0.617021 (-2940 2335);
PAINT ORANGE (-2940 2335);
FORCEPROP 2 LASTPIN (-3950 2275) $PN 5
J 2
(-3960 2285);
DISPLAY 0.617021 (-3960 2285);
PAINT ORANGE (-3960 2285);
FORCEPROP 2 LAST SEC_TYPE SM
J 0
(-3900 4125);
DISPLAY 1.021277 (-3900 4125);
PAINT ORANGE (-3900 4125);
DISPLAY INVISIBLE (-3900 4125);
FORCEPROP 1 LAST PACK_TYPE SM
J 0
(-3900 4125);
PAINT SKYBLUE (-3900 4125);
DISPLAY INVISIBLE (-3900 4125);
FORCEPROP 2 LAST SEC 1
J 0
(-3900 4125);
DISPLAY 0.680851 (-3900 4125);
PAINT MONO (-3900 4125);
DISPLAY INVISIBLE (-3900 4125);
FORCEPROP 2 LAST CDS_LOCATION EU7F1
J 0
(-3900 4075);
DISPLAY 0.617021 (-3900 4075);
PAINT AQUA (-3900 4075);
DISPLAY INVISIBLE (-3900 4075);
FORCEPROP 2 LAST CDS_LIB mstr_vreg
J 0
(-3450 3125);
PAINT ORANGE (-3450 3125);
DISPLAY INVISIBLE (-3450 3125);
FORCEPROP 1 LAST CDS_LMAN_SYM_OUTLINE -450,850,450,-900
J 0
(-3450 3125);
DISPLAY 0.468085 (-3450 3125);
PAINT GREEN (-3450 3125);
DISPLAY INVISIBLE (-3450 3125);
FORCEPROP 1 LAST PATH I193
J 0
(-3400 4025);
PAINT GREEN (-3400 4025);
DISPLAY INVISIBLE (-3400 4025);
FORCEADD CAP..1
(-4725 2425);
FORCEPROP 1 LAST VALUE 0.027UF
J 0
(-4675 2475);
DISPLAY 0.617021 (-4675 2475);
PAINT SKYBLUE (-4675 2475);
FORCEPROP 1 LAST VOLTAGE 16V
J 0
(-4650 2425);
DISPLAY 0.617021 (-4650 2425);
PAINT SKYBLUE (-4650 2425);
FORCEPROP 1 LAST PART_NUMBER A36096-129
J 0
(-4700 2275);
DISPLAY 0.617021 (-4700 2275);
PAINT BLUE (-4700 2275);
FORCEPROP 1 LAST TOLERANCE 10%
J 0
(-4650 2375);
DISPLAY 0.617021 (-4650 2375);
PAINT SKYBLUE (-4650 2375);
FORCEPROP 1 LAST MATERIAL X7R
J 0
(-4675 2225);
DISPLAY 0.617021 (-4675 2225);
PAINT SKYBLUE (-4675 2225);
FORCEPROP 1 LASTPIN (-4725 2325) $PN 2
J 0
(-4715 2305);
DISPLAY 0.617021 (-4715 2305);
PAINT ORANGE (-4715 2305);
FORCEPROP 1 LASTPIN (-4725 2525) $PN 1
J 0
(-4715 2505);
DISPLAY 0.617021 (-4715 2505);
PAINT ORANGE (-4715 2505);
FORCEPROP 1 LAST LOCATION C7F10
J 0
(-4675 2525);
DISPLAY 0.617021 (-4675 2525);
PAINT AQUA (-4675 2525);
FORCEPROP 1 LAST PACK_TYPE 0402
J 0
(-4675 2325);
DISPLAY 0.617021 (-4675 2325);
PAINT SKYBLUE (-4675 2325);
FORCEPROP 1 LAST PATH I194
J 0
(-4675 2575);
DISPLAY 0.978723 (-4675 2575);
PAINT WHITE (-4675 2575);
DISPLAY INVISIBLE (-4675 2575);
FORCEPROP 2 LAST SEC 1
J 0
(-4675 2625);
PAINT MONO (-4675 2625);
DISPLAY INVISIBLE (-4675 2625);
FORCEPROP 2 LAST SEC_TYPE 0402
J 0
(-4675 2625);
DISPLAY 1.021277 (-4675 2625);
PAINT ORANGE (-4675 2625);
DISPLAY INVISIBLE (-4675 2625);
FORCEPROP 2 LAST REUSE_ID 26
J 0
(-4675 2625);
DISPLAY 1.042553 (-4675 2625);
PAINT ORANGE (-4675 2625);
DISPLAY INVISIBLE (-4675 2625);
FORCEPROP 2 LAST BOM_COST PVPP_KLM_VR
J 0
(-4675 2575);
DISPLAY 1.042553 (-4675 2575);
PAINT WHITE (-4675 2575);
DISPLAY INVISIBLE (-4675 2575);
FORCEPROP 2 LAST ROOM PVPP_KLM_VR
J 0
(-4675 2550);
PAINT GREEN (-4675 2550);
DISPLAY INVISIBLE (-4675 2550);
FORCEPROP 2 LAST CDS_LIB mstr_discrete
J 0
(-4725 2425);
PAINT MONO (-4725 2425);
DISPLAY INVISIBLE (-4725 2425);
FORCEPROP 2 LAST CDS_LOCATION C7F10
J 0
(-4675 2525);
DISPLAY 0.617021 (-4675 2525);
PAINT AQUA (-4675 2525);
DISPLAY INVISIBLE (-4675 2525);
FORCEADD AGND_SCSI..1
(-4725 2200);
FORCEPROP 3 LASTPIN (-4725 2250) SIG_NAME AGND_PVPP_ABC\g
J 0
(-4715 2260);
DISPLAY 0.659574 (-4715 2260);
PAINT MONO (-4715 2260);
DISPLAY INVISIBLE (-4715 2260);
FORCEPROP 1 LAST HDL_POWER AGND_PVPP_ABC
J 1
(-4700 2125);
DISPLAY 0.617021 (-4700 2125);
PAINT GREEN (-4700 2125);
FORCEPROP 1 LAST BODY_TYPE PLUMBING
J 0
(-4770 2157);
DISPLAY 0.340426 (-4770 2157);
PAINT GREEN (-4770 2157);
DISPLAY INVISIBLE (-4770 2157);
FORCEPROP 1 LAST VOLTAGE 0.0V
J 0
(-4770 2157);
DISPLAY 0.340426 (-4770 2157);
PAINT SKYBLUE (-4770 2157);
DISPLAY INVISIBLE (-4770 2157);
FORCEPROP 2 LAST CDS_LIB mstr_symbols
J 0
(-4725 2200);
PAINT MONO (-4725 2200);
DISPLAY INVISIBLE (-4725 2200);
FORCEPROP 1 LAST PATH I195
J 0
(-4650 2200);
DISPLAY 0.872340 (-4650 2200);
PAINT AQUA (-4650 2200);
DISPLAY INVISIBLE (-4650 2200);
FORCEPROP 2 LAST BOM_COST PVPP_KLM_VR
J 0
(-4875 2150);
DISPLAY 1.042553 (-4875 2150);
PAINT WHITE (-4875 2150);
DISPLAY INVISIBLE (-4875 2150);
FORCEPROP 2 LAST ROOM PVPP_KLM_VR
J 0
(-4875 2150);
DISPLAY 1.042553 (-4875 2150);
PAINT GREEN (-4875 2150);
DISPLAY INVISIBLE (-4875 2150);
FORCEADD GND..1
(-2725 2175);
FORCEPROP 3 LASTPIN (-2725 2225) SIG_NAME GND\g
J 0
(-2715 2235);
DISPLAY 0.659574 (-2715 2235);
PAINT MONO (-2715 2235);
DISPLAY INVISIBLE (-2715 2235);
FORCEPROP 1 LAST HDL_POWER GND
J 0
(-2725 2400);
DISPLAY 0.893617 (-2725 2400);
PAINT GREEN (-2725 2400);
DISPLAY INVISIBLE (-2725 2400);
FORCEPROP 1 LAST BODY_TYPE PLUMBING
J 0
(-2770 2132);
DISPLAY 0.340426 (-2770 2132);
PAINT GREEN (-2770 2132);
DISPLAY INVISIBLE (-2770 2132);
FORCEPROP 1 LAST SIZE 1B
J 0
(-2650 2200);
DISPLAY 0.893617 (-2650 2200);
PAINT GREEN (-2650 2200);
DISPLAY INVISIBLE (-2650 2200);
FORCEPROP 1 LAST PATH I196
J 0
(-2650 2175);
DISPLAY 0.872340 (-2650 2175);
PAINT AQUA (-2650 2175);
DISPLAY INVISIBLE (-2650 2175);
FORCEPROP 1 LAST VOLTAGE 0
J 0
(-2725 2250);
PAINT SKYBLUE (-2725 2250);
DISPLAY INVISIBLE (-2725 2250);
FORCEPROP 2 LAST CDS_LIB mstr_symbols
J 0
(-2725 2175);
PAINT MONO (-2725 2175);
DISPLAY INVISIBLE (-2725 2175);
FORCEPROP 2 LAST ROOM PVPP_KLM_VR
J 0
(-3375 2325);
PAINT GREEN (-3375 2325);
DISPLAY INVISIBLE (-3375 2325);
FORCEPROP 2 LAST BOM_COST PVPP_KLM_VR
J 0
(-3625 2325);
DISPLAY 1.042553 (-3625 2325);
PAINT WHITE (-3625 2325);
DISPLAY INVISIBLE (-3625 2325);
FORCEADD CAP..2
R 2
(-1875 3075);
FORCEPROP 1 LAST VALUE 100.0PF
J 0
(-1975 2975);
DISPLAY 0.617021 (-1975 2975);
PAINT SKYBLUE (-1975 2975);
FORCEPROP 1 LAST VOLTAGE 50V
J 2
(-2050 2975);
DISPLAY 0.617021 (-2050 2975);
PAINT SKYBLUE (-2050 2975);
FORCEPROP 1 LAST PART_NUMBER A36095-026
J 1
(-2075 2925);
DISPLAY 0.617021 (-2075 2925);
PAINT BLUE (-2075 2925);
FORCEPROP 1 LAST MATERIAL COG
J 2
(-1650 2925);
DISPLAY 0.617021 (-1650 2925);
PAINT SKYBLUE (-1650 2925);
FORCEPROP 1 LAST PACK_TYPE 0402LF
J 1
(-1850 2925);
DISPLAY 0.617021 (-1850 2925);
PAINT SKYBLUE (-1850 2925);
FORCEPROP 1 LAST LOCATION C7F9
J 1
(-1875 3125);
DISPLAY 0.617021 (-1875 3125);
PAINT AQUA (-1875 3125);
FORCEPROP 1 LASTPIN (-1775 3075) $PN 1
J 2
(-1765 3090);
DISPLAY 0.617021 (-1765 3090);
PAINT ORANGE (-1765 3090);
FORCEPROP 1 LASTPIN (-1975 3075) $PN 2
J 2
(-1960 3090);
DISPLAY 0.617021 (-1960 3090);
PAINT ORANGE (-1960 3090);
FORCEPROP 1 LAST TOLERANCE 5%
J 0
(-1700 2975);
DISPLAY 0.617021 (-1700 2975);
PAINT SKYBLUE (-1700 2975);
FORCEPROP 2 LAST SEC_TYPE 0402LF
J 0
(-1875 3325);
DISPLAY 1.021277 (-1875 3325);
PAINT ORANGE (-1875 3325);
DISPLAY INVISIBLE (-1875 3325);
FORCEPROP 2 LAST REUSE_ID 27
J 0
(-1875 3325);
DISPLAY 1.042553 (-1875 3325);
PAINT ORANGE (-1875 3325);
DISPLAY INVISIBLE (-1875 3325);
FORCEPROP 2 LAST SEC 1
J 0
(-1875 3325);
DISPLAY 0.680851 (-1875 3325);
PAINT MONO (-1875 3325);
DISPLAY INVISIBLE (-1875 3325);
FORCEPROP 2 LAST CDS_LIB mstr_discrete
J 0
(-1875 3075);
PAINT ORANGE (-1875 3075);
DISPLAY INVISIBLE (-1875 3075);
FORCEPROP 2 LAST BOM_COST PVPP_KLM_VR
J 0
(-1920 3235);
DISPLAY 1.042553 (-1920 3235);
PAINT WHITE (-1920 3235);
DISPLAY INVISIBLE (-1920 3235);
FORCEPROP 2 LAST CDS_LOCATION C7F9
J 1
(-1875 3125);
DISPLAY 0.617021 (-1875 3125);
PAINT AQUA (-1875 3125);
DISPLAY INVISIBLE (-1875 3125);
FORCEPROP 1 LAST PATH I199
J 2
(-1875 3275);
DISPLAY 0.978723 (-1875 3275);
PAINT WHITE (-1875 3275);
DISPLAY INVISIBLE (-1875 3275);
FORCEPROP 2 LAST ROOM PVPP_KLM_VR
J 2
(-1875 3200);
DISPLAY 0.765957 (-1875 3200);
PAINT GREEN (-1875 3200);
DISPLAY INVISIBLE (-1875 3200);
FORCEADD CAP..2
R 2
(-2500 2700);
FORCEPROP 1 LAST LOCATION C7F12
J 1
(-2500 2775);
DISPLAY 0.617021 (-2500 2775);
PAINT AQUA (-2500 2775);
FORCEPROP 1 LAST PART_NUMBER A36096-075
J 1
(-2475 2625);
DISPLAY 0.617021 (-2475 2625);
PAINT BLUE (-2475 2625);
FORCEPROP 1 LAST VALUE 2200PF
J 0
(-2475 2575);
DISPLAY 0.617021 (-2475 2575);
PAINT SKYBLUE (-2475 2575);
FORCEPROP 1 LAST PACK_TYPE 0402LF
J 1
(-2500 2475);
DISPLAY 0.617021 (-2500 2475);
PAINT SKYBLUE (-2500 2475);
FORCEPROP 1 LASTPIN (-2600 2700) $PN 2
J 2
(-2585 2715);
DISPLAY 0.617021 (-2585 2715);
PAINT ORANGE (-2585 2715);
FORCEPROP 1 LASTPIN (-2400 2700) $PN 1
J 2
(-2390 2715);
DISPLAY 0.617021 (-2390 2715);
PAINT ORANGE (-2390 2715);
FORCEPROP 1 LAST MATERIAL X7R
J 2
(-2500 2525);
DISPLAY 0.617021 (-2500 2525);
PAINT SKYBLUE (-2500 2525);
FORCEPROP 1 LAST VOLTAGE 50V
J 2
(-2500 2575);
DISPLAY 0.617021 (-2500 2575);
PAINT SKYBLUE (-2500 2575);
FORCEPROP 1 LAST TOLERANCE 10%
J 0
(-2500 2525);
DISPLAY 0.617021 (-2500 2525);
PAINT SKYBLUE (-2500 2525);
FORCEPROP 2 LAST SEC_TYPE 0402LF
J 0
(-2500 2950);
DISPLAY 1.021277 (-2500 2950);
PAINT ORANGE (-2500 2950);
DISPLAY INVISIBLE (-2500 2950);
FORCEPROP 2 LAST CDS_LIB mstr_discrete
J 0
(-2500 2700);
PAINT ORANGE (-2500 2700);
DISPLAY INVISIBLE (-2500 2700);
FORCEPROP 2 LAST REUSE_ID 27
J 0
(-2500 2950);
DISPLAY 1.042553 (-2500 2950);
PAINT ORANGE (-2500 2950);
DISPLAY INVISIBLE (-2500 2950);
FORCEPROP 2 LAST BOM_COST PVPP_KLM_VR
J 0
(-2545 2860);
DISPLAY 1.042553 (-2545 2860);
PAINT WHITE (-2545 2860);
DISPLAY INVISIBLE (-2545 2860);
FORCEPROP 2 LAST SEC 1
J 0
(-2500 2950);
DISPLAY 0.680851 (-2500 2950);
PAINT MONO (-2500 2950);
DISPLAY INVISIBLE (-2500 2950);
FORCEPROP 2 LAST CDS_LOCATION C7F12
J 1
(-2500 2775);
DISPLAY 0.617021 (-2500 2775);
PAINT AQUA (-2500 2775);
DISPLAY INVISIBLE (-2500 2775);
FORCEPROP 1 LAST PATH I200
J 2
(-2500 2900);
DISPLAY 0.978723 (-2500 2900);
PAINT WHITE (-2500 2900);
DISPLAY INVISIBLE (-2500 2900);
FORCEPROP 2 LAST ROOM PVPP_KLM_VR
J 2
(-2500 2825);
DISPLAY 0.765957 (-2500 2825);
PAINT GREEN (-2500 2825);
DISPLAY INVISIBLE (-2500 2825);
FORCEADD RES..1
(-1800 2700);
FORCEPROP 1 LAST VALUE 7.87K
J 2
(-1900 2575);
DISPLAY 0.617021 (-1900 2575);
PAINT SKYBLUE (-1900 2575);
FORCEPROP 1 LAST WATTAGE 1/16W
J 2
(-1825 2525);
DISPLAY 0.617021 (-1825 2525);
PAINT SKYBLUE (-1825 2525);
FORCEPROP 1 LAST MATERIAL CHIP
J 0
(-1800 2525);
DISPLAY 0.617021 (-1800 2525);
PAINT SKYBLUE (-1800 2525);
FORCEPROP 1 LAST PACK_TYPE 0402
J 0
(-1750 2575);
DISPLAY 0.617021 (-1750 2575);
PAINT SKYBLUE (-1750 2575);
FORCEPROP 1 LASTPIN (-1700 2700) $PN 2
J 0
(-1738 2712);
DISPLAY 0.617021 (-1738 2712);
PAINT ORANGE (-1738 2712);
FORCEPROP 1 LASTPIN (-1900 2700) $PN 1
J 0
(-1888 2712);
DISPLAY 0.617021 (-1888 2712);
PAINT ORANGE (-1888 2712);
FORCEPROP 1 LAST TOLERANCE 1.0%
J 0
(-1850 2575);
DISPLAY 0.617021 (-1850 2575);
PAINT SKYBLUE (-1850 2575);
FORCEPROP 1 LAST LOCATION R7F18
J 0
(-1850 2750);
DISPLAY 0.617021 (-1850 2750);
PAINT AQUA (-1850 2750);
FORCEPROP 1 LAST PART_NUMBER G21796-242
J 0
(-1950 2625);
DISPLAY 0.617021 (-1950 2625);
PAINT BLUE (-1950 2625);
FORCEPROP 2 LAST REUSE_ID 13
J 0
(-1850 2900);
DISPLAY 1.042553 (-1850 2900);
PAINT ORANGE (-1850 2900);
DISPLAY INVISIBLE (-1850 2900);
FORCEPROP 2 LAST SEC 1
J 0
(-1850 2900);
PAINT MONO (-1850 2900);
DISPLAY INVISIBLE (-1850 2900);
FORCEPROP 1 LAST PATH I201
J 0
(-1850 2850);
DISPLAY 0.978723 (-1850 2850);
PAINT WHITE (-1850 2850);
DISPLAY INVISIBLE (-1850 2850);
FORCEPROP 2 LAST SEC_TYPE 0402
J 0
(-1850 2900);
DISPLAY 1.021277 (-1850 2900);
PAINT ORANGE (-1850 2900);
DISPLAY INVISIBLE (-1850 2900);
FORCEPROP 2 LAST ROOM PVPP_KLM_VR
J 0
(-1800 2700);
PAINT GREEN (-1800 2700);
DISPLAY INVISIBLE (-1800 2700);
FORCEPROP 2 LAST CDS_LOCATION R7F18
J 0
(-1850 2750);
DISPLAY 0.617021 (-1850 2750);
PAINT AQUA (-1850 2750);
DISPLAY INVISIBLE (-1850 2750);
FORCEPROP 2 LAST BOM_COST PVPP_KLM_VR
J 0
(-1800 2700);
PAINT WHITE (-1800 2700);
DISPLAY INVISIBLE (-1800 2700);
FORCEPROP 2 LAST CDS_LIB mstr_discrete
J 0
(-1800 2700);
PAINT MONO (-1800 2700);
DISPLAY INVISIBLE (-1800 2700);
FORCEADD CAP..1
(-5375 2625);
FORCEPROP 0 LAST CONFIG 078.47521.08BD
J 0
(-5600 2400);
DISPLAY 0.638298 (-5600 2400);
PAINT BROWN (-5600 2400);
DISPLAY BOTH (-5600 2400);
FORCEPROP 1 LAST LOCATION C3T11
J 0
(-5325 2725);
DISPLAY 0.617021 (-5325 2725);
PAINT AQUA (-5325 2725);
FORCEPROP 1 LASTPIN (-5375 2525) $PN 2
J 0
(-5365 2505);
DISPLAY 0.617021 (-5365 2505);
PAINT ORANGE (-5365 2505);
FORCEPROP 1 LAST PACK_TYPE 0603
J 0
(-5325 2525);
DISPLAY 0.617021 (-5325 2525);
PAINT SKYBLUE (-5325 2525);
FORCEPROP 1 LAST TOLERANCE 10%
J 0
(-5300 2575);
DISPLAY 0.617021 (-5300 2575);
PAINT SKYBLUE (-5300 2575);
FORCEPROP 1 LAST PART_NUMBER E15431-003
J 0
(-5350 2475);
DISPLAY 0.617021 (-5350 2475);
PAINT BLUE (-5350 2475);
FORCEPROP 1 LAST VOLTAGE 6.3V
J 0
(-5300 2625);
DISPLAY 0.617021 (-5300 2625);
PAINT SKYBLUE (-5300 2625);
FORCEPROP 1 LAST MATERIAL X6S
J 0
(-5325 2425);
DISPLAY 0.617021 (-5325 2425);
PAINT SKYBLUE (-5325 2425);
FORCEPROP 1 LAST VALUE 4.7UF
J 0
(-5325 2675);
DISPLAY 0.617021 (-5325 2675);
PAINT SKYBLUE (-5325 2675);
FORCEPROP 1 LASTPIN (-5375 2725) $PN 1
J 0
(-5365 2705);
DISPLAY 0.617021 (-5365 2705);
PAINT ORANGE (-5365 2705);
FORCEPROP 2 LAST SEC 1
J 0
(-5325 2825);
PAINT MONO (-5325 2825);
DISPLAY INVISIBLE (-5325 2825);
FORCEPROP 2 LAST REUSE_ID 26
J 0
(-5325 2825);
DISPLAY 1.042553 (-5325 2825);
PAINT ORANGE (-5325 2825);
DISPLAY INVISIBLE (-5325 2825);
FORCEPROP 2 LAST SEC_TYPE 0603
J 0
(-5325 2825);
DISPLAY 1.021277 (-5325 2825);
PAINT ORANGE (-5325 2825);
DISPLAY INVISIBLE (-5325 2825);
FORCEPROP 2 LAST BOM_COST PVPP_KLM_VR
J 0
(-5325 2775);
DISPLAY 1.042553 (-5325 2775);
PAINT WHITE (-5325 2775);
DISPLAY INVISIBLE (-5325 2775);
FORCEPROP 1 LAST PATH I202
J 0
(-5325 2775);
DISPLAY 0.978723 (-5325 2775);
PAINT WHITE (-5325 2775);
DISPLAY INVISIBLE (-5325 2775);
FORCEPROP 2 LAST CDS_LOCATION C3T11
J 0
(-5325 2725);
DISPLAY 0.617021 (-5325 2725);
PAINT AQUA (-5325 2725);
DISPLAY INVISIBLE (-5325 2725);
FORCEPROP 2 LAST CDS_LIB mstr_discrete
J 0
(-5375 2625);
PAINT MONO (-5375 2625);
DISPLAY INVISIBLE (-5375 2625);
FORCEPROP 2 LAST ROOM PVPP_KLM_VR
J 0
(-5325 2750);
PAINT GREEN (-5325 2750);
DISPLAY INVISIBLE (-5325 2750);
FORCEADD AGND_SCSI..1
(-5375 2325);
FORCEPROP 3 LASTPIN (-5375 2375) SIG_NAME AGND_PVPP_ABC\g
J 0
(-5365 2385);
DISPLAY 0.659574 (-5365 2385);
PAINT MONO (-5365 2385);
DISPLAY INVISIBLE (-5365 2385);
FORCEPROP 1 LAST HDL_POWER AGND_PVPP_ABC
J 1
(-5350 2250);
DISPLAY 0.617021 (-5350 2250);
PAINT GREEN (-5350 2250);
FORCEPROP 1 LAST BODY_TYPE PLUMBING
J 0
(-5420 2282);
DISPLAY 0.340426 (-5420 2282);
PAINT GREEN (-5420 2282);
DISPLAY INVISIBLE (-5420 2282);
FORCEPROP 1 LAST PATH I203
J 0
(-5300 2325);
DISPLAY 0.872340 (-5300 2325);
PAINT AQUA (-5300 2325);
DISPLAY INVISIBLE (-5300 2325);
FORCEPROP 2 LAST CDS_LIB mstr_symbols
J 0
(-5375 2325);
PAINT MONO (-5375 2325);
DISPLAY INVISIBLE (-5375 2325);
FORCEPROP 2 LAST ROOM PVPP_KLM_VR
J 0
(-5525 2275);
DISPLAY 1.042553 (-5525 2275);
PAINT GREEN (-5525 2275);
DISPLAY INVISIBLE (-5525 2275);
FORCEPROP 2 LAST BOM_COST PVPP_KLM_VR
J 0
(-5525 2275);
DISPLAY 1.042553 (-5525 2275);
PAINT WHITE (-5525 2275);
DISPLAY INVISIBLE (-5525 2275);
FORCEPROP 1 LAST VOLTAGE 0.0V
J 0
(-5420 2282);
DISPLAY 0.340426 (-5420 2282);
PAINT SKYBLUE (-5420 2282);
DISPLAY INVISIBLE (-5420 2282);
FORCEADD AGND_SCSI..1
(-5025 2950);
FORCEPROP 3 LASTPIN (-5025 3000) SIG_NAME AGND_PVPP_ABC\g
J 0
(-5015 3010);
DISPLAY 0.659574 (-5015 3010);
PAINT MONO (-5015 3010);
DISPLAY INVISIBLE (-5015 3010);
FORCEPROP 1 LAST HDL_POWER AGND_PVPP_ABC
J 1
(-5000 2875);
DISPLAY 0.617021 (-5000 2875);
PAINT GREEN (-5000 2875);
FORCEPROP 1 LAST BODY_TYPE PLUMBING
J 0
(-5070 2907);
DISPLAY 0.340426 (-5070 2907);
PAINT GREEN (-5070 2907);
DISPLAY INVISIBLE (-5070 2907);
FORCEPROP 1 LAST PATH I204
J 0
(-4950 2950);
DISPLAY 0.872340 (-4950 2950);
PAINT AQUA (-4950 2950);
DISPLAY INVISIBLE (-4950 2950);
FORCEPROP 2 LAST CDS_LIB mstr_symbols
J 0
(-5025 2950);
PAINT MONO (-5025 2950);
DISPLAY INVISIBLE (-5025 2950);
FORCEPROP 1 LAST VOLTAGE 0.0V
J 0
(-5070 2907);
DISPLAY 0.340426 (-5070 2907);
PAINT SKYBLUE (-5070 2907);
DISPLAY INVISIBLE (-5070 2907);
FORCEPROP 2 LAST ROOM PVPP_KLM_VR
J 0
(-5175 2900);
DISPLAY 1.042553 (-5175 2900);
PAINT GREEN (-5175 2900);
DISPLAY INVISIBLE (-5175 2900);
FORCEPROP 2 LAST BOM_COST PVPP_KLM_VR
J 0
(-5175 2900);
DISPLAY 1.042553 (-5175 2900);
PAINT WHITE (-5175 2900);
DISPLAY INVISIBLE (-5175 2900);
FORCEADD CAP_A..1
(-4775 3750);
FORCEPROP 1 LAST VALUE 0.1UF
J 0
(-4725 3800);
DISPLAY 0.617021 (-4725 3800);
PAINT SKYBLUE (-4725 3800);
FORCEPROP 1 LAST PACK_TYPE 0402V
J 0
(-4725 3550);
DISPLAY 0.617021 (-4725 3550);
PAINT SKYBLUE (-4725 3550);
FORCEPROP 1 LAST LOCATION C7F6
J 0
(-4725 3850);
DISPLAY 0.617021 (-4725 3850);
PAINT AQUA (-4725 3850);
FORCEPROP 1 LASTPIN (-4775 3850) $PN 1
J 0
(-4765 3830);
DISPLAY 0.617021 (-4765 3830);
PAINT ORANGE (-4765 3830);
FORCEPROP 1 LAST TOLERANCE 10%
J 0
(-4725 3700);
DISPLAY 0.617021 (-4725 3700);
PAINT SKYBLUE (-4725 3700);
FORCEPROP 1 LAST VOLTAGE 16V
J 0
(-4725 3750);
DISPLAY 0.617021 (-4725 3750);
PAINT SKYBLUE (-4725 3750);
FORCEPROP 1 LASTPIN (-4775 3650) $PN 2
J 0
(-4765 3630);
DISPLAY 0.617021 (-4765 3630);
PAINT ORANGE (-4765 3630);
FORCEPROP 1 LAST MATERIAL X7R
J 0
(-4725 3650);
DISPLAY 0.617021 (-4725 3650);
PAINT SKYBLUE (-4725 3650);
FORCEPROP 1 LAST PART_NUMBER A36096-030
J 0
(-4725 3600);
DISPLAY 0.617021 (-4725 3600);
PAINT BLUE (-4725 3600);
FORCEPROP 1 LAST PATH I205
J 0
(-4725 3900);
DISPLAY 0.978723 (-4725 3900);
PAINT WHITE (-4725 3900);
DISPLAY INVISIBLE (-4725 3900);
FORCEPROP 2 LAST CDS_LOCATION C7F6
J 0
(-4725 3850);
DISPLAY 0.617021 (-4725 3850);
PAINT AQUA (-4725 3850);
DISPLAY INVISIBLE (-4725 3850);
FORCEPROP 2 LAST CDS_SEC 1
J 0
(-4725 3900);
PAINT ORANGE (-4725 3900);
DISPLAY INVISIBLE (-4725 3900);
FORCEPROP 2 LAST SEC_TYPE 0402V
J 0
(-4725 3950);
DISPLAY 1.021277 (-4725 3950);
PAINT ORANGE (-4725 3950);
DISPLAY INVISIBLE (-4725 3950);
FORCEPROP 2 LAST SEC 1
J 0
(-4725 3950);
PAINT MONO (-4725 3950);
DISPLAY INVISIBLE (-4725 3950);
FORCEPROP 2 LAST CDS_LIB dev_discrete
J 0
(-4775 3750);
PAINT ORANGE (-4775 3750);
DISPLAY INVISIBLE (-4775 3750);
FORCEADD GND..1
(-4775 3525);
FORCEPROP 3 LASTPIN (-4775 3575) SIG_NAME GND\g
J 0
(-4765 3585);
DISPLAY 0.659574 (-4765 3585);
PAINT MONO (-4765 3585);
DISPLAY INVISIBLE (-4765 3585);
FORCEPROP 1 LAST HDL_POWER GND
J 0
(-4775 3675);
DISPLAY 0.872340 (-4775 3675);
PAINT GREEN (-4775 3675);
DISPLAY INVISIBLE (-4775 3675);
FORCEPROP 1 LAST BODY_TYPE PLUMBING
J 0
(-4820 3482);
DISPLAY 0.340426 (-4820 3482);
PAINT GREEN (-4820 3482);
DISPLAY INVISIBLE (-4820 3482);
FORCEPROP 1 LAST VOLTAGE 0
J 0
(-4775 3525);
PAINT SKYBLUE (-4775 3525);
DISPLAY INVISIBLE (-4775 3525);
FORCEPROP 1 LAST SIZE 1B
J 0
(-4700 3475);
DISPLAY 0.872340 (-4700 3475);
PAINT GREEN (-4700 3475);
DISPLAY INVISIBLE (-4700 3475);
FORCEPROP 2 LAST CDS_LIB mstr_symbols
J 0
(-4775 3525);
PAINT MONO (-4775 3525);
DISPLAY INVISIBLE (-4775 3525);
FORCEPROP 1 LAST PATH I206
J 0
(-4700 3525);
DISPLAY 0.872340 (-4700 3525);
PAINT AQUA (-4700 3525);
DISPLAY INVISIBLE (-4700 3525);
FORCEPROP 2 LAST BOM_COST PVPP_KLM_VR
J 0
(-5625 3600);
DISPLAY 1.042553 (-5625 3600);
PAINT WHITE (-5625 3600);
DISPLAY INVISIBLE (-5625 3600);
FORCEPROP 2 LAST ROOM PVPP_KLM_VR
J 0
(-5350 3600);
DISPLAY 1.042553 (-5350 3600);
PAINT GREEN (-5350 3600);
DISPLAY INVISIBLE (-5350 3600);
FORCEADD RES..1
(-3000 1225);
FORCEPROP 1 LAST MATERIAL CHIP
J 0
(-3000 1075);
DISPLAY 0.617021 (-3000 1075);
PAINT SKYBLUE (-3000 1075);
FORCEPROP 1 LAST VALUE 22.1
J 2
(-3025 1125);
DISPLAY 0.617021 (-3025 1125);
PAINT SKYBLUE (-3025 1125);
FORCEPROP 1 LAST PACK_TYPE 0402
J 0
(-2750 1075);
DISPLAY 0.617021 (-2750 1075);
PAINT SKYBLUE (-2750 1075);
FORCEPROP 1 LAST PART_NUMBER G21796-250
J 0
(-3050 1325);
DISPLAY 0.617021 (-3050 1325);
PAINT BLUE (-3050 1325);
FORCEPROP 1 LAST LOCATION R7F16
J 0
(-3050 1275);
DISPLAY 0.617021 (-3050 1275);
PAINT AQUA (-3050 1275);
FORCEPROP 1 LAST TOLERANCE 1.0%
J 0
(-3000 1125);
DISPLAY 0.617021 (-3000 1125);
PAINT SKYBLUE (-3000 1125);
FORCEPROP 1 LASTPIN (-2900 1225) $PN 2
J 0
(-2938 1237);
DISPLAY 0.617021 (-2938 1237);
PAINT ORANGE (-2938 1237);
FORCEPROP 1 LAST WATTAGE 1/16W
J 2
(-3025 1075);
DISPLAY 0.617021 (-3025 1075);
PAINT SKYBLUE (-3025 1075);
FORCEPROP 1 LASTPIN (-3100 1225) $PN 1
J 0
(-3088 1237);
DISPLAY 0.617021 (-3088 1237);
PAINT ORANGE (-3088 1237);
FORCEPROP 2 LAST ROOM PVPP_KLM_VR
J 0
(-3050 1325);
DISPLAY 1.361702 (-3050 1325);
PAINT ORANGE (-3050 1325);
DISPLAY INVISIBLE (-3050 1325);
FORCEPROP 1 LAST PATH I208
J 0
(-3050 1375);
DISPLAY 0.978723 (-3050 1375);
PAINT WHITE (-3050 1375);
DISPLAY INVISIBLE (-3050 1375);
FORCEPROP 2 LAST SEC_TYPE 0402
J 0
(-3050 1425);
DISPLAY 1.021277 (-3050 1425);
PAINT ORANGE (-3050 1425);
DISPLAY INVISIBLE (-3050 1425);
FORCEPROP 2 LAST SEC 1
J 0
(-3050 1425);
DISPLAY 0.680851 (-3050 1425);
PAINT MONO (-3050 1425);
DISPLAY INVISIBLE (-3050 1425);
FORCEPROP 2 LAST CDS_LOCATION R7F16
J 0
(-3050 1275);
DISPLAY 0.617021 (-3050 1275);
PAINT AQUA (-3050 1275);
DISPLAY INVISIBLE (-3050 1275);
FORCEPROP 2 LAST CDS_LIB mstr_discrete
J 0
(-3000 1225);
PAINT MONO (-3000 1225);
DISPLAY INVISIBLE (-3000 1225);
FORCEADD CAP..1
(-6225 4375);
FORCEPROP 1 LASTPIN (-6225 4475) $PN 1
J 0
(-6215 4455);
DISPLAY 0.617021 (-6215 4455);
PAINT ORANGE (-6215 4455);
FORCEPROP 1 LAST PACK_TYPE 0805
J 0
(-6175 4175);
DISPLAY 0.617021 (-6175 4175);
PAINT SKYBLUE (-6175 4175);
FORCEPROP 1 LAST MATERIAL X6S
J 0
(-6175 4275);
DISPLAY 0.617021 (-6175 4275);
PAINT SKYBLUE (-6175 4275);
FORCEPROP 1 LAST TOLERANCE 10%
J 0
(-6175 4325);
DISPLAY 0.617021 (-6175 4325);
PAINT SKYBLUE (-6175 4325);
FORCEPROP 1 LAST VOLTAGE 16V
J 0
(-6175 4375);
DISPLAY 0.617021 (-6175 4375);
PAINT SKYBLUE (-6175 4375);
FORCEPROP 1 LAST VALUE 10UF
J 0
(-6175 4425);
DISPLAY 0.617021 (-6175 4425);
PAINT SKYBLUE (-6175 4425);
FORCEPROP 1 LAST LOCATION C7F5
J 0
(-6175 4475);
DISPLAY 0.617021 (-6175 4475);
PAINT AQUA (-6175 4475);
FORCEPROP 1 LASTPIN (-6225 4275) $PN 2
J 0
(-6215 4255);
DISPLAY 0.617021 (-6215 4255);
PAINT ORANGE (-6215 4255);
FORCEPROP 1 LAST PART_NUMBER C95333-007
J 0
(-6175 4225);
DISPLAY 0.617021 (-6175 4225);
PAINT BLUE (-6175 4225);
FORCEPROP 2 LAST SEC_TYPE 0805
J 0
(-6175 4575);
DISPLAY 1.021277 (-6175 4575);
PAINT ORANGE (-6175 4575);
DISPLAY INVISIBLE (-6175 4575);
FORCEPROP 1 LAST PATH I209
J 0
(-6175 4525);
DISPLAY 0.978723 (-6175 4525);
PAINT WHITE (-6175 4525);
DISPLAY INVISIBLE (-6175 4525);
FORCEPROP 2 LAST CDS_LOCATION C7F5
J 0
(-6175 4475);
DISPLAY 0.617021 (-6175 4475);
PAINT AQUA (-6175 4475);
DISPLAY INVISIBLE (-6175 4475);
FORCEPROP 2 LAST SEC 1
J 0
(-6175 4575);
DISPLAY 0.680851 (-6175 4575);
PAINT MONO (-6175 4575);
DISPLAY INVISIBLE (-6175 4575);
FORCEPROP 2 LAST CDS_LIB mstr_discrete
J 0
(-6225 4375);
PAINT MONO (-6225 4375);
DISPLAY INVISIBLE (-6225 4375);
FORCEADD CAP..1
(-5825 4375);
FORCEPROP 1 LAST VALUE 10UF
J 0
(-5775 4425);
DISPLAY 0.617021 (-5775 4425);
PAINT SKYBLUE (-5775 4425);
FORCEPROP 1 LAST LOCATION C3T8
J 0
(-5775 4475);
DISPLAY 0.617021 (-5775 4475);
PAINT AQUA (-5775 4475);
FORCEPROP 1 LASTPIN (-5825 4475) $PN 1
J 0
(-5815 4455);
DISPLAY 0.617021 (-5815 4455);
PAINT ORANGE (-5815 4455);
FORCEPROP 1 LAST PACK_TYPE 0805
J 0
(-5775 4175);
DISPLAY 0.617021 (-5775 4175);
PAINT SKYBLUE (-5775 4175);
FORCEPROP 1 LAST PART_NUMBER C95333-007
J 0
(-5775 4225);
DISPLAY 0.617021 (-5775 4225);
PAINT BLUE (-5775 4225);
FORCEPROP 1 LAST TOLERANCE 10%
J 0
(-5775 4325);
DISPLAY 0.617021 (-5775 4325);
PAINT SKYBLUE (-5775 4325);
FORCEPROP 1 LAST VOLTAGE 16V
J 0
(-5775 4375);
DISPLAY 0.617021 (-5775 4375);
PAINT SKYBLUE (-5775 4375);
FORCEPROP 1 LAST MATERIAL X6S
J 0
(-5775 4275);
DISPLAY 0.617021 (-5775 4275);
PAINT SKYBLUE (-5775 4275);
FORCEPROP 1 LASTPIN (-5825 4275) $PN 2
J 0
(-5815 4255);
DISPLAY 0.617021 (-5815 4255);
PAINT ORANGE (-5815 4255);
FORCEPROP 2 LAST SEC_TYPE 0805
J 0
(-5775 4575);
DISPLAY 1.021277 (-5775 4575);
PAINT ORANGE (-5775 4575);
DISPLAY INVISIBLE (-5775 4575);
FORCEPROP 2 LAST SEC 1
J 0
(-5775 4575);
DISPLAY 0.680851 (-5775 4575);
PAINT MONO (-5775 4575);
DISPLAY INVISIBLE (-5775 4575);
FORCEPROP 2 LAST CDS_LOCATION C3T8
J 0
(-5775 4475);
DISPLAY 0.617021 (-5775 4475);
PAINT AQUA (-5775 4475);
DISPLAY INVISIBLE (-5775 4475);
FORCEPROP 1 LAST PATH I210
J 0
(-5775 4525);
DISPLAY 0.978723 (-5775 4525);
PAINT WHITE (-5775 4525);
DISPLAY INVISIBLE (-5775 4525);
FORCEPROP 2 LAST CDS_LIB mstr_discrete
J 0
(-5825 4375);
PAINT MONO (-5825 4375);
DISPLAY INVISIBLE (-5825 4375);
FORCEADD CAP..1
(-5425 4375);
FORCEPROP 1 LAST LOCATION C3T14
J 0
(-5375 4475);
DISPLAY 0.617021 (-5375 4475);
PAINT AQUA (-5375 4475);
FORCEPROP 1 LAST VALUE 10UF
J 0
(-5375 4425);
DISPLAY 0.617021 (-5375 4425);
PAINT SKYBLUE (-5375 4425);
FORCEPROP 1 LASTPIN (-5425 4475) $PN 1
J 0
(-5415 4455);
DISPLAY 0.617021 (-5415 4455);
PAINT ORANGE (-5415 4455);
FORCEPROP 1 LAST PART_NUMBER C95333-007
J 0
(-5375 4225);
DISPLAY 0.617021 (-5375 4225);
PAINT BLUE (-5375 4225);
FORCEPROP 1 LAST TOLERANCE 10%
J 0
(-5375 4325);
DISPLAY 0.617021 (-5375 4325);
PAINT SKYBLUE (-5375 4325);
FORCEPROP 1 LAST VOLTAGE 16V
J 0
(-5375 4375);
DISPLAY 0.617021 (-5375 4375);
PAINT SKYBLUE (-5375 4375);
FORCEPROP 1 LAST MATERIAL X6S
J 0
(-5375 4275);
DISPLAY 0.617021 (-5375 4275);
PAINT SKYBLUE (-5375 4275);
FORCEPROP 1 LASTPIN (-5425 4275) $PN 2
J 0
(-5415 4255);
DISPLAY 0.617021 (-5415 4255);
PAINT ORANGE (-5415 4255);
FORCEPROP 1 LAST PACK_TYPE 0805
J 0
(-5375 4175);
DISPLAY 0.617021 (-5375 4175);
PAINT SKYBLUE (-5375 4175);
FORCEPROP 2 LAST SEC_TYPE 0805
J 0
(-5375 4575);
DISPLAY 1.021277 (-5375 4575);
PAINT ORANGE (-5375 4575);
DISPLAY INVISIBLE (-5375 4575);
FORCEPROP 1 LAST PATH I211
J 0
(-5375 4525);
DISPLAY 0.978723 (-5375 4525);
PAINT WHITE (-5375 4525);
DISPLAY INVISIBLE (-5375 4525);
FORCEPROP 2 LAST CDS_LOCATION C3T14
J 0
(-5375 4475);
DISPLAY 0.617021 (-5375 4475);
PAINT AQUA (-5375 4475);
DISPLAY INVISIBLE (-5375 4475);
FORCEPROP 2 LAST SEC 1
J 0
(-5375 4575);
DISPLAY 0.680851 (-5375 4575);
PAINT MONO (-5375 4575);
DISPLAY INVISIBLE (-5375 4575);
FORCEPROP 2 LAST CDS_LIB mstr_discrete
J 0
(-5425 4375);
PAINT MONO (-5425 4375);
DISPLAY INVISIBLE (-5425 4375);
FORCEADD GND..1
(-5425 4175);
FORCEPROP 3 LASTPIN (-5425 4225) SIG_NAME GND\g
J 0
(-5415 4235);
DISPLAY 0.659574 (-5415 4235);
PAINT MONO (-5415 4235);
DISPLAY INVISIBLE (-5415 4235);
FORCEPROP 1 LAST HDL_POWER GND
J 0
(-5425 4325);
DISPLAY 0.872340 (-5425 4325);
PAINT GREEN (-5425 4325);
DISPLAY INVISIBLE (-5425 4325);
FORCEPROP 1 LAST BODY_TYPE PLUMBING
J 0
(-5470 4132);
DISPLAY 0.340426 (-5470 4132);
PAINT GREEN (-5470 4132);
DISPLAY INVISIBLE (-5470 4132);
FORCEPROP 1 LAST PATH I212
J 0
(-5350 4175);
DISPLAY 0.872340 (-5350 4175);
PAINT AQUA (-5350 4175);
DISPLAY INVISIBLE (-5350 4175);
FORCEPROP 2 LAST CDS_LIB mstr_symbols
J 0
(-5425 4175);
PAINT MONO (-5425 4175);
DISPLAY INVISIBLE (-5425 4175);
FORCEPROP 1 LAST SIZE 1B
J 0
(-5350 4125);
DISPLAY 0.872340 (-5350 4125);
PAINT GREEN (-5350 4125);
DISPLAY INVISIBLE (-5350 4125);
FORCEPROP 1 LAST VOLTAGE 0
J 0
(-5425 4175);
PAINT SKYBLUE (-5425 4175);
DISPLAY INVISIBLE (-5425 4175);
FORCEPROP 2 LAST ROOM PVPP_KLM_VR
J 0
(-6000 4250);
DISPLAY 1.042553 (-6000 4250);
PAINT GREEN (-6000 4250);
DISPLAY INVISIBLE (-6000 4250);
FORCEPROP 2 LAST BOM_COST PVPP_KLM_VR
J 0
(-6275 4250);
DISPLAY 1.042553 (-6275 4250);
PAINT WHITE (-6275 4250);
DISPLAY INVISIBLE (-6275 4250);
FORCEADD GND..1
(-5825 4175);
FORCEPROP 3 LASTPIN (-5825 4225) SIG_NAME GND\g
J 0
(-5815 4235);
DISPLAY 0.659574 (-5815 4235);
PAINT MONO (-5815 4235);
DISPLAY INVISIBLE (-5815 4235);
FORCEPROP 1 LAST HDL_POWER GND
J 0
(-5825 4325);
DISPLAY 0.872340 (-5825 4325);
PAINT GREEN (-5825 4325);
DISPLAY INVISIBLE (-5825 4325);
FORCEPROP 1 LAST BODY_TYPE PLUMBING
J 0
(-5870 4132);
DISPLAY 0.340426 (-5870 4132);
PAINT GREEN (-5870 4132);
DISPLAY INVISIBLE (-5870 4132);
FORCEPROP 1 LAST SIZE 1B
J 0
(-5750 4125);
DISPLAY 0.872340 (-5750 4125);
PAINT GREEN (-5750 4125);
DISPLAY INVISIBLE (-5750 4125);
FORCEPROP 1 LAST PATH I213
J 0
(-5750 4175);
DISPLAY 0.872340 (-5750 4175);
PAINT AQUA (-5750 4175);
DISPLAY INVISIBLE (-5750 4175);
FORCEPROP 2 LAST CDS_LIB mstr_symbols
J 0
(-5825 4175);
PAINT MONO (-5825 4175);
DISPLAY INVISIBLE (-5825 4175);
FORCEPROP 1 LAST VOLTAGE 0
J 0
(-5825 4175);
PAINT SKYBLUE (-5825 4175);
DISPLAY INVISIBLE (-5825 4175);
FORCEPROP 2 LAST ROOM PVPP_KLM_VR
J 0
(-6400 4250);
DISPLAY 1.042553 (-6400 4250);
PAINT GREEN (-6400 4250);
DISPLAY INVISIBLE (-6400 4250);
FORCEPROP 2 LAST BOM_COST PVPP_KLM_VR
J 0
(-6675 4250);
DISPLAY 1.042553 (-6675 4250);
PAINT WHITE (-6675 4250);
DISPLAY INVISIBLE (-6675 4250);
FORCEADD GND..1
(-6225 4175);
FORCEPROP 3 LASTPIN (-6225 4225) SIG_NAME GND\g
J 0
(-6215 4235);
DISPLAY 0.659574 (-6215 4235);
PAINT MONO (-6215 4235);
DISPLAY INVISIBLE (-6215 4235);
FORCEPROP 1 LAST HDL_POWER GND
J 0
(-6225 4325);
DISPLAY 0.872340 (-6225 4325);
PAINT GREEN (-6225 4325);
DISPLAY INVISIBLE (-6225 4325);
FORCEPROP 1 LAST BODY_TYPE PLUMBING
J 0
(-6270 4132);
DISPLAY 0.340426 (-6270 4132);
PAINT GREEN (-6270 4132);
DISPLAY INVISIBLE (-6270 4132);
FORCEPROP 1 LAST PATH I214
J 0
(-6150 4175);
DISPLAY 0.872340 (-6150 4175);
PAINT AQUA (-6150 4175);
DISPLAY INVISIBLE (-6150 4175);
FORCEPROP 1 LAST SIZE 1B
J 0
(-6150 4125);
DISPLAY 0.872340 (-6150 4125);
PAINT GREEN (-6150 4125);
DISPLAY INVISIBLE (-6150 4125);
FORCEPROP 2 LAST CDS_LIB mstr_symbols
J 0
(-6225 4175);
PAINT MONO (-6225 4175);
DISPLAY INVISIBLE (-6225 4175);
FORCEPROP 1 LAST VOLTAGE 0
J 0
(-6225 4175);
PAINT SKYBLUE (-6225 4175);
DISPLAY INVISIBLE (-6225 4175);
FORCEPROP 2 LAST ROOM PVPP_KLM_VR
J 0
(-6800 4250);
DISPLAY 1.042553 (-6800 4250);
PAINT GREEN (-6800 4250);
DISPLAY INVISIBLE (-6800 4250);
FORCEPROP 2 LAST BOM_COST PVPP_KLM_VR
J 0
(-7075 4250);
DISPLAY 1.042553 (-7075 4250);
PAINT WHITE (-7075 4250);
DISPLAY INVISIBLE (-7075 4250);
FORCEADD CAP..1
(-5075 4375);
FORCEPROP 1 LAST VOLTAGE 16V
J 0
(-5025 4375);
DISPLAY 0.617021 (-5025 4375);
PAINT SKYBLUE (-5025 4375);
FORCEPROP 1 LAST VALUE 10UF
J 0
(-5025 4425);
DISPLAY 0.617021 (-5025 4425);
PAINT SKYBLUE (-5025 4425);
FORCEPROP 1 LAST LOCATION C3T12
J 0
(-5025 4475);
DISPLAY 0.617021 (-5025 4475);
PAINT AQUA (-5025 4475);
FORCEPROP 1 LASTPIN (-5075 4475) $PN 1
J 0
(-5065 4455);
DISPLAY 0.617021 (-5065 4455);
PAINT ORANGE (-5065 4455);
FORCEPROP 1 LAST MATERIAL X6S
J 0
(-5025 4275);
DISPLAY 0.617021 (-5025 4275);
PAINT SKYBLUE (-5025 4275);
FORCEPROP 1 LAST PACK_TYPE 0805
J 0
(-5025 4175);
DISPLAY 0.617021 (-5025 4175);
PAINT SKYBLUE (-5025 4175);
FORCEPROP 1 LASTPIN (-5075 4275) $PN 2
J 0
(-5065 4255);
DISPLAY 0.617021 (-5065 4255);
PAINT ORANGE (-5065 4255);
FORCEPROP 1 LAST TOLERANCE 10%
J 0
(-5025 4325);
DISPLAY 0.617021 (-5025 4325);
PAINT SKYBLUE (-5025 4325);
FORCEPROP 1 LAST PART_NUMBER C95333-007
J 0
(-5025 4225);
DISPLAY 0.617021 (-5025 4225);
PAINT BLUE (-5025 4225);
FORCEPROP 2 LAST SEC_TYPE 0805
J 0
(-5025 4575);
DISPLAY 1.021277 (-5025 4575);
PAINT ORANGE (-5025 4575);
DISPLAY INVISIBLE (-5025 4575);
FORCEPROP 2 LAST SEC 1
J 0
(-5025 4575);
DISPLAY 0.680851 (-5025 4575);
PAINT MONO (-5025 4575);
DISPLAY INVISIBLE (-5025 4575);
FORCEPROP 1 LAST PATH I215
J 0
(-5025 4525);
DISPLAY 0.978723 (-5025 4525);
PAINT WHITE (-5025 4525);
DISPLAY INVISIBLE (-5025 4525);
FORCEPROP 2 LAST CDS_LOCATION C3T12
J 0
(-5025 4475);
DISPLAY 0.617021 (-5025 4475);
PAINT AQUA (-5025 4475);
DISPLAY INVISIBLE (-5025 4475);
FORCEPROP 2 LAST CDS_LIB mstr_discrete
J 0
(-5075 4375);
PAINT MONO (-5075 4375);
DISPLAY INVISIBLE (-5075 4375);
FORCEADD GND..1
(-5075 4175);
FORCEPROP 3 LASTPIN (-5075 4225) SIG_NAME GND\g
J 0
(-5065 4235);
DISPLAY 0.659574 (-5065 4235);
PAINT MONO (-5065 4235);
DISPLAY INVISIBLE (-5065 4235);
FORCEPROP 1 LAST HDL_POWER GND
J 0
(-5075 4325);
DISPLAY 0.872340 (-5075 4325);
PAINT GREEN (-5075 4325);
DISPLAY INVISIBLE (-5075 4325);
FORCEPROP 1 LAST BODY_TYPE PLUMBING
J 0
(-5120 4132);
DISPLAY 0.340426 (-5120 4132);
PAINT GREEN (-5120 4132);
DISPLAY INVISIBLE (-5120 4132);
FORCEPROP 1 LAST VOLTAGE 0
J 0
(-5075 4175);
PAINT SKYBLUE (-5075 4175);
DISPLAY INVISIBLE (-5075 4175);
FORCEPROP 1 LAST SIZE 1B
J 0
(-5000 4125);
DISPLAY 0.872340 (-5000 4125);
PAINT GREEN (-5000 4125);
DISPLAY INVISIBLE (-5000 4125);
FORCEPROP 2 LAST CDS_LIB mstr_symbols
J 0
(-5075 4175);
PAINT MONO (-5075 4175);
DISPLAY INVISIBLE (-5075 4175);
FORCEPROP 1 LAST PATH I216
J 0
(-5000 4175);
DISPLAY 0.872340 (-5000 4175);
PAINT AQUA (-5000 4175);
DISPLAY INVISIBLE (-5000 4175);
FORCEPROP 2 LAST ROOM PVPP_KLM_VR
J 0
(-5650 4250);
DISPLAY 1.042553 (-5650 4250);
PAINT GREEN (-5650 4250);
DISPLAY INVISIBLE (-5650 4250);
FORCEPROP 2 LAST BOM_COST PVPP_KLM_VR
J 0
(-5925 4250);
DISPLAY 1.042553 (-5925 4250);
PAINT WHITE (-5925 4250);
DISPLAY INVISIBLE (-5925 4250);
FORCEADD CAPP..1
(-1100 3900);
FORCEPROP 1 LAST PACK_TYPE 7343
J 0
(-1050 3800);
DISPLAY 0.617021 (-1050 3800);
PAINT SKYBLUE (-1050 3800);
FORCEPROP 1 LAST VOLTAGE 4V
J 0
(-1050 3900);
DISPLAY 0.617021 (-1050 3900);
PAINT SKYBLUE (-1050 3900);
FORCEPROP 1 LAST TOLERANCE 20%
J 0
(-1050 3950);
DISPLAY 0.617021 (-1050 3950);
PAINT SKYBLUE (-1050 3950);
FORCEPROP 1 LAST VALUE 220UF
J 0
(-1050 4000);
DISPLAY 0.617021 (-1050 4000);
PAINT SKYBLUE (-1050 4000);
FORCEPROP 1 LAST LOCATION C4T3
J 0
(-1050 4050);
DISPLAY 0.617021 (-1050 4050);
PAINT AQUA (-1050 4050);
FORCEPROP 1 LASTPIN (-1100 3800) $PN 2
J 0
(-1090 3785);
DISPLAY 0.617021 (-1090 3785);
PAINT ORANGE (-1090 3785);
FORCEPROP 1 LASTPIN (-1100 4000) $PN 1
J 0
(-1090 3985);
DISPLAY 0.617021 (-1090 3985);
PAINT ORANGE (-1090 3985);
FORCEPROP 1 LAST MATERIAL POSCAP
J 0
(-1050 3850);
DISPLAY 0.617021 (-1050 3850);
PAINT SKYBLUE (-1050 3850);
FORCEPROP 1 LAST PART_NUMBER 724613-067
J 0
(-1050 3750);
DISPLAY 0.617021 (-1050 3750);
PAINT BLUE (-1050 3750);
FORCEPROP 0 LAST GROUP PWR_BULK_CAP
J 0
(-1035 3651);
DISPLAY 0.638298 (-1035 3651);
PAINT BROWN (-1035 3651);
DISPLAY BOTH (-1035 3651);
FORCEPROP 2 LAST CDS_LIB mstr_discrete
J 0
(-1100 3900);
PAINT ORANGE (-1100 3900);
DISPLAY INVISIBLE (-1100 3900);
FORCEPROP 1 LAST PATH I217
J 0
(-1050 4050);
DISPLAY 0.978723 (-1050 4050);
PAINT ORANGE (-1050 4050);
DISPLAY INVISIBLE (-1050 4050);
FORCEPROP 2 LAST CDS_LOCATION C4T3
J 0
(-1050 4000);
DISPLAY 0.617021 (-1050 4000);
PAINT AQUA (-1050 4000);
DISPLAY INVISIBLE (-1050 4000);
FORCEPROP 2 LAST SEC 1
J 0
(-1050 4100);
DISPLAY 0.680851 (-1050 4100);
PAINT MONO (-1050 4100);
DISPLAY INVISIBLE (-1050 4100);
FORCEPROP 2 LAST SEC_TYPE 7343
J 0
(-1050 4100);
DISPLAY 1.021277 (-1050 4100);
PAINT ORANGE (-1050 4100);
DISPLAY INVISIBLE (-1050 4100);
FORCEADD RES..2
(-675 2800);
FORCEPROP 1 LAST PART_NUMBER G85996-004
J 0
(-660 2625);
DISPLAY 0.617021 (-660 2625);
PAINT BLUE (-660 2625);
FORCEPROP 1 LAST MATERIAL CHIP
J 0
(-635 2675);
DISPLAY 0.617021 (-635 2675);
PAINT SKYBLUE (-635 2675);
FORCEPROP 1 LAST PACK_TYPE 0402
J 0
(-635 2725);
DISPLAY 0.617021 (-635 2725);
PAINT SKYBLUE (-635 2725);
FORCEPROP 1 LAST WATTAGE 1/16W
J 0
(-635 2775);
DISPLAY 0.617021 (-635 2775);
PAINT SKYBLUE (-635 2775);
FORCEPROP 1 LAST TOLERANCE 0.1%
J 0
(-630 2825);
DISPLAY 0.617021 (-630 2825);
PAINT SKYBLUE (-630 2825);
FORCEPROP 1 LASTPIN (-675 2700) $PN 2
J 0
(-670 2710);
DISPLAY 0.617021 (-670 2710);
PAINT ORANGE (-670 2710);
FORCEPROP 1 LASTPIN (-675 2900) $PN 1
J 0
(-670 2862);
DISPLAY 0.617021 (-670 2862);
PAINT ORANGE (-670 2862);
FORCEPROP 1 LAST VALUE 1.0K
J 0
(-630 2875);
DISPLAY 0.617021 (-630 2875);
PAINT SKYBLUE (-630 2875);
FORCEPROP 1 LAST LOCATION R7F17
J 0
(-630 2925);
DISPLAY 0.617021 (-630 2925);
PAINT AQUA (-630 2925);
FORCEPROP 2 LAST CDS_LIB mstr_discrete
J 0
(-675 2800);
PAINT MONO (-675 2800);
DISPLAY INVISIBLE (-675 2800);
FORCEPROP 2 LAST CDS_LOCATION R7F17
J 0
(-630 2925);
DISPLAY 0.617021 (-630 2925);
PAINT AQUA (-630 2925);
DISPLAY INVISIBLE (-630 2925);
FORCEPROP 2 LAST ROOM PVPP_KLM_VR
J 0
(-630 2955);
PAINT GREEN (-630 2955);
DISPLAY INVISIBLE (-630 2955);
FORCEPROP 1 LAST PATH I218
J 0
(-625 2975);
DISPLAY 0.978723 (-625 2975);
PAINT WHITE (-625 2975);
DISPLAY INVISIBLE (-625 2975);
FORCEPROP 2 LAST BOM_COST PVPP_KLM_VR
J 0
(-630 2980);
DISPLAY 1.042553 (-630 2980);
PAINT WHITE (-630 2980);
DISPLAY INVISIBLE (-630 2980);
FORCEPROP 0 LAST SPOF TRUE
J 0
(-625 3025);
DISPLAY 1.021277 (-625 3025);
PAINT ORANGE (-625 3025);
DISPLAY INVISIBLE (-625 3025);
FORCEPROP 2 LAST SEC_TYPE 0402
J 0
(-625 3025);
DISPLAY 1.021277 (-625 3025);
PAINT ORANGE (-625 3025);
DISPLAY INVISIBLE (-625 3025);
FORCEPROP 2 LAST REUSE_ID 9
J 0
(-625 3025);
DISPLAY 1.042553 (-625 3025);
PAINT ORANGE (-625 3025);
DISPLAY INVISIBLE (-625 3025);
FORCEPROP 2 LAST SEC 1
J 0
(-625 3025);
DISPLAY 0.680851 (-625 3025);
PAINT MONO (-625 3025);
DISPLAY INVISIBLE (-625 3025);
FORCEADD CAP..1
(-675 2000);
FORCEPROP 1 LAST PART_NUMBER A36096-075
J 0
(-625 1850);
DISPLAY 0.617021 (-625 1850);
PAINT BLUE (-625 1850);
FORCEPROP 1 LAST MATERIAL X7R
J 0
(-625 1900);
DISPLAY 0.617021 (-625 1900);
PAINT SKYBLUE (-625 1900);
FORCEPROP 1 LAST TOLERANCE 10%
J 0
(-625 1950);
DISPLAY 0.617021 (-625 1950);
PAINT SKYBLUE (-625 1950);
FORCEPROP 1 LAST VALUE 2200PF
J 0
(-625 2050);
DISPLAY 0.617021 (-625 2050);
PAINT SKYBLUE (-625 2050);
FORCEPROP 1 LAST PACK_TYPE 0402LF
J 0
(-625 1800);
DISPLAY 0.617021 (-625 1800);
PAINT SKYBLUE (-625 1800);
FORCEPROP 1 LAST LOCATION C7F13
J 0
(-625 2100);
DISPLAY 0.617021 (-625 2100);
PAINT AQUA (-625 2100);
FORCEPROP 1 LASTPIN (-675 2100) $PN 1
J 0
(-665 2080);
DISPLAY 0.617021 (-665 2080);
PAINT ORANGE (-665 2080);
FORCEPROP 1 LAST VOLTAGE 50V
J 0
(-625 2000);
DISPLAY 0.617021 (-625 2000);
PAINT SKYBLUE (-625 2000);
FORCEPROP 1 LASTPIN (-675 1900) $PN 2
J 0
(-665 1880);
DISPLAY 0.617021 (-665 1880);
PAINT ORANGE (-665 1880);
FORCEPROP 2 LAST BOM_COST PVPP_KLM_VR
J 0
(-625 2150);
DISPLAY 1.042553 (-625 2150);
PAINT WHITE (-625 2150);
DISPLAY INVISIBLE (-625 2150);
FORCEPROP 2 LAST CDS_LIB mstr_discrete
J 0
(-675 2000);
PAINT ORANGE (-675 2000);
DISPLAY INVISIBLE (-675 2000);
FORCEPROP 2 LAST SEC 1
J 0
(-625 2200);
DISPLAY 0.680851 (-625 2200);
PAINT MONO (-625 2200);
DISPLAY INVISIBLE (-625 2200);
FORCEPROP 2 LAST CDS_LOCATION C7F13
J 0
(-625 2100);
DISPLAY 0.617021 (-625 2100);
PAINT AQUA (-625 2100);
DISPLAY INVISIBLE (-625 2100);
FORCEPROP 1 LAST PATH I219
J 0
(-625 2150);
DISPLAY 0.978723 (-625 2150);
PAINT WHITE (-625 2150);
DISPLAY INVISIBLE (-625 2150);
FORCEPROP 2 LAST ROOM PVPP_KLM_VR
J 0
(-625 2125);
PAINT GREEN (-625 2125);
DISPLAY INVISIBLE (-625 2125);
FORCEPROP 2 LAST REUSE_ID 26
J 0
(-625 2200);
DISPLAY 1.042553 (-625 2200);
PAINT ORANGE (-625 2200);
DISPLAY INVISIBLE (-625 2200);
FORCEPROP 0 LAST SPOF TRUE
J 0
(-625 2200);
DISPLAY 1.021277 (-625 2200);
PAINT ORANGE (-625 2200);
DISPLAY INVISIBLE (-625 2200);
FORCEPROP 2 LAST SEC_TYPE 0402LF
J 0
(-625 2200);
DISPLAY 1.021277 (-625 2200);
PAINT ORANGE (-625 2200);
DISPLAY INVISIBLE (-625 2200);
FORCEADD RES..1
(-5775 3075);
FORCEPROP 1 LASTPIN (-5675 3075) $PN 2
J 0
(-5713 3087);
DISPLAY 0.617021 (-5713 3087);
PAINT ORANGE (-5713 3087);
FORCEPROP 1 LAST LOCATION R7F9
J 0
(-5825 3125);
DISPLAY 0.617021 (-5825 3125);
PAINT AQUA (-5825 3125);
FORCEPROP 1 LASTPIN (-5875 3075) $PN 1
J 0
(-5863 3087);
DISPLAY 0.617021 (-5863 3087);
PAINT ORANGE (-5863 3087);
FORCEPROP 1 LAST PART_NUMBER G21497-005
J 0
(-5925 3025);
DISPLAY 0.617021 (-5925 3025);
PAINT BLUE (-5925 3025);
FORCEPROP 1 LAST TOLERANCE 5%
J 0
(-5825 2975);
DISPLAY 0.617021 (-5825 2975);
PAINT SKYBLUE (-5825 2975);
FORCEPROP 1 LAST VALUE 0.0
J 2
(-5875 2975);
DISPLAY 0.617021 (-5875 2975);
PAINT SKYBLUE (-5875 2975);
FORCEPROP 1 LAST WATTAGE 1/16W
J 2
(-5800 2925);
DISPLAY 0.617021 (-5800 2925);
PAINT SKYBLUE (-5800 2925);
FORCEPROP 1 LAST MATERIAL CHIP
J 0
(-5775 2925);
DISPLAY 0.617021 (-5775 2925);
PAINT SKYBLUE (-5775 2925);
FORCEPROP 1 LAST PACK_TYPE 0402
J 0
(-5700 2975);
DISPLAY 0.617021 (-5700 2975);
PAINT SKYBLUE (-5700 2975);
FORCEPROP 2 LAST ROOM PVCCIN_CPU0_VR
J 0
(-5825 3175);
DISPLAY 1.361702 (-5825 3175);
PAINT ORANGE (-5825 3175);
DISPLAY INVISIBLE (-5825 3175);
FORCEPROP 1 LAST PATH I220
J 0
(-5825 3225);
DISPLAY 0.978723 (-5825 3225);
PAINT WHITE (-5825 3225);
DISPLAY INVISIBLE (-5825 3225);
FORCEPROP 2 LAST CDS_LOCATION R7F9
J 0
(-5825 3125);
DISPLAY 0.617021 (-5825 3125);
PAINT AQUA (-5825 3125);
DISPLAY INVISIBLE (-5825 3125);
FORCEPROP 2 LAST SEC 1
J 0
(-5825 3275);
PAINT MONO (-5825 3275);
DISPLAY INVISIBLE (-5825 3275);
FORCEPROP 2 LAST SEC_TYPE 0402
J 0
(-5825 3275);
DISPLAY 1.021277 (-5825 3275);
PAINT ORANGE (-5825 3275);
DISPLAY INVISIBLE (-5825 3275);
FORCEPROP 2 LAST CDS_LIB mstr_discrete
J 0
(-5775 3075);
PAINT ORANGE (-5775 3075);
DISPLAY INVISIBLE (-5775 3075);
FORCEADD GND..1
(-6650 4150);
FORCEPROP 3 LASTPIN (-6650 4200) SIG_NAME GND\g
J 0
(-6640 4210);
DISPLAY 0.659574 (-6640 4210);
PAINT MONO (-6640 4210);
DISPLAY INVISIBLE (-6640 4210);
FORCEPROP 1 LAST HDL_POWER GND
J 0
(-6650 4300);
DISPLAY 0.872340 (-6650 4300);
PAINT GREEN (-6650 4300);
DISPLAY INVISIBLE (-6650 4300);
FORCEPROP 1 LAST BODY_TYPE PLUMBING
J 0
(-6695 4107);
DISPLAY 0.340426 (-6695 4107);
PAINT GREEN (-6695 4107);
DISPLAY INVISIBLE (-6695 4107);
FORCEPROP 1 LAST PATH I222
J 0
(-6575 4150);
DISPLAY 0.872340 (-6575 4150);
PAINT AQUA (-6575 4150);
DISPLAY INVISIBLE (-6575 4150);
FORCEPROP 2 LAST CDS_LIB mstr_symbols
J 0
(-6650 4150);
PAINT MONO (-6650 4150);
DISPLAY INVISIBLE (-6650 4150);
FORCEPROP 2 LAST BOM_COST PVPP_KLM_VR
J 0
(-7500 4225);
DISPLAY 1.042553 (-7500 4225);
PAINT WHITE (-7500 4225);
DISPLAY INVISIBLE (-7500 4225);
FORCEPROP 2 LAST ROOM PVPP_KLM_VR
J 0
(-7225 4225);
DISPLAY 1.042553 (-7225 4225);
PAINT GREEN (-7225 4225);
DISPLAY INVISIBLE (-7225 4225);
FORCEPROP 1 LAST VOLTAGE 0
J 0
(-6650 4150);
PAINT SKYBLUE (-6650 4150);
DISPLAY INVISIBLE (-6650 4150);
FORCEPROP 1 LAST SIZE 1B
J 0
(-6575 4100);
DISPLAY 0.872340 (-6575 4100);
PAINT GREEN (-6575 4100);
DISPLAY INVISIBLE (-6575 4100);
FORCEADD SC22U16V5MX-4-GP..1
(-6650 4325);
FORCEPROP 2 LAST PACK_SIZE 0805
J 0
(-6550 4175);
DISPLAY 0.638298 (-6550 4175);
PAINT GREEN (-6550 4175);
FORCEPROP 2 LAST TYPE X6S
J 0
(-6550 4225);
DISPLAY 0.638298 (-6550 4225);
PAINT GREEN (-6550 4225);
FORCEPROP 2 LAST RATED 16V
J 0
(-6550 4275);
DISPLAY 0.638298 (-6550 4275);
PAINT GREEN (-6550 4275);
FORCEPROP 2 LAST TOLERANCE 20%
J 0
(-6550 4325);
DISPLAY 0.638298 (-6550 4325);
PAINT GREEN (-6550 4325);
FORCEPROP 2 LAST ATTRIBUTE 22UF
J 0
(-6550 4375);
DISPLAY 0.638298 (-6550 4375);
PAINT GREEN (-6550 4375);
FORCEPROP 2 LASTPIN (-6650 4250) $PN 2
R 1
J 2
(-6660 4240);
DISPLAY 0.808511 (-6660 4240);
PAINT ORANGE (-6660 4240);
FORCEPROP 2 LASTPIN (-6650 4400) $PN 1
R 1
J 0
(-6660 4410);
DISPLAY 0.808511 (-6660 4410);
PAINT ORANGE (-6660 4410);
FORCEPROP 1 LAST LOCATION C22W10
J 0
(-6550 4435);
DISPLAY 0.617021 (-6550 4435);
PAINT GREEN (-6550 4435);
FORCEPROP 1 LAST VALUE SC22U16V5MX-4-GP
R 1
J 0
(-6575 4120);
DISPLAY 0.617021 (-6575 4120);
PAINT GREEN (-6575 4120);
FORCEPROP 1 LAST PACK_TYPE SMD-BCG5
J 0
(-6650 4325);
DISPLAY 0.617021 (-6650 4325);
PAINT GREEN (-6650 4325);
DISPLAY INVISIBLE (-6650 4325);
FORCEPROP 2 LAST SEC 1
J 0
(-6625 4400);
DISPLAY 0.680851 (-6625 4400);
PAINT MONO (-6625 4400);
DISPLAY INVISIBLE (-6625 4400);
FORCEPROP 2 LAST SEC_TYPE SMD-BCG5
J 0
(-6625 4400);
DISPLAY 1.021277 (-6625 4400);
PAINT ORANGE (-6625 4400);
DISPLAY INVISIBLE (-6625 4400);
FORCEPROP 1 LAST PART_NUMBER 078.22611.0811
J 0
(-6650 4325);
DISPLAY 0.617021 (-6650 4325);
PAINT GREEN (-6650 4325);
DISPLAY INVISIBLE (-6650 4325);
FORCEPROP 2 LAST CDS_LIB w_hdl
J 0
(-6650 4325);
PAINT MONO (-6650 4325);
DISPLAY INVISIBLE (-6650 4325);
FORCEPROP 1 LAST CDS_LMAN_SYM_OUTLINE -50,25,50,-25
J 0
(-6650 4325);
DISPLAY 0.468085 (-6650 4325);
PAINT GREEN (-6650 4325);
DISPLAY INVISIBLE (-6650 4325);
FORCEPROP 1 LAST PATH I225
J 0
(-6650 4325);
DISPLAY 0.617021 (-6650 4325);
PAINT GREEN (-6650 4325);
DISPLAY INVISIBLE (-6650 4325);
FORCEADD SC22U16V5MX-4-GP..1
(-6950 4325);
FORCEPROP 2 LASTPIN (-6950 4250) $PN 2
R 1
J 2
(-6960 4240);
DISPLAY 0.808511 (-6960 4240);
PAINT ORANGE (-6960 4240);
FORCEPROP 2 LAST PACK_SIZE 0805
J 0
(-6850 4175);
DISPLAY 0.638298 (-6850 4175);
PAINT GREEN (-6850 4175);
FORCEPROP 2 LAST TYPE X6S
J 0
(-6850 4225);
DISPLAY 0.638298 (-6850 4225);
PAINT GREEN (-6850 4225);
FORCEPROP 2 LAST RATED 16V
J 0
(-6850 4275);
DISPLAY 0.638298 (-6850 4275);
PAINT GREEN (-6850 4275);
FORCEPROP 2 LAST TOLERANCE 20%
J 0
(-6850 4325);
DISPLAY 0.638298 (-6850 4325);
PAINT GREEN (-6850 4325);
FORCEPROP 2 LAST ATTRIBUTE 22UF
J 0
(-6850 4375);
DISPLAY 0.638298 (-6850 4375);
PAINT GREEN (-6850 4375);
FORCEPROP 1 LAST LOCATION C7F7
J 0
(-6850 4435);
DISPLAY 0.617021 (-6850 4435);
PAINT GREEN (-6850 4435);
FORCEPROP 2 LASTPIN (-6950 4400) $PN 1
R 1
J 0
(-6960 4410);
DISPLAY 0.808511 (-6960 4410);
PAINT ORANGE (-6960 4410);
FORCEPROP 1 LAST VALUE SC22U16V5MX-4-GP
R 1
J 0
(-6875 4120);
DISPLAY 0.617021 (-6875 4120);
PAINT GREEN (-6875 4120);
FORCEPROP 1 LAST PATH I226
J 0
(-6950 4325);
DISPLAY 0.617021 (-6950 4325);
PAINT GREEN (-6950 4325);
DISPLAY INVISIBLE (-6950 4325);
FORCEPROP 1 LAST PACK_TYPE SMD-BCG5
J 0
(-6950 4325);
DISPLAY 0.617021 (-6950 4325);
PAINT GREEN (-6950 4325);
DISPLAY INVISIBLE (-6950 4325);
FORCEPROP 2 LAST SEC 1
J 0
(-6925 4400);
DISPLAY 0.680851 (-6925 4400);
PAINT MONO (-6925 4400);
DISPLAY INVISIBLE (-6925 4400);
FORCEPROP 2 LAST SEC_TYPE SMD-BCG5
J 0
(-6925 4400);
DISPLAY 1.021277 (-6925 4400);
PAINT ORANGE (-6925 4400);
DISPLAY INVISIBLE (-6925 4400);
FORCEPROP 1 LAST PART_NUMBER 078.22611.0811
J 0
(-6950 4325);
DISPLAY 0.617021 (-6950 4325);
PAINT GREEN (-6950 4325);
DISPLAY INVISIBLE (-6950 4325);
FORCEPROP 2 LAST CDS_LIB w_hdl
J 0
(-6950 4325);
PAINT MONO (-6950 4325);
DISPLAY INVISIBLE (-6950 4325);
FORCEPROP 1 LAST CDS_LMAN_SYM_OUTLINE -50,25,50,-25
J 0
(-6950 4325);
DISPLAY 0.468085 (-6950 4325);
PAINT GREEN (-6950 4325);
DISPLAY INVISIBLE (-6950 4325);
FORCEADD GND..1
(-6950 4150);
FORCEPROP 3 LASTPIN (-6950 4200) SIG_NAME GND\g
J 0
(-6940 4210);
DISPLAY 0.659574 (-6940 4210);
PAINT MONO (-6940 4210);
DISPLAY INVISIBLE (-6940 4210);
FORCEPROP 1 LAST HDL_POWER GND
J 0
(-6950 4300);
DISPLAY 0.872340 (-6950 4300);
PAINT GREEN (-6950 4300);
DISPLAY INVISIBLE (-6950 4300);
FORCEPROP 1 LAST BODY_TYPE PLUMBING
J 0
(-6995 4107);
DISPLAY 0.340426 (-6995 4107);
PAINT GREEN (-6995 4107);
DISPLAY INVISIBLE (-6995 4107);
FORCEPROP 1 LAST PATH I228
J 0
(-6875 4150);
DISPLAY 0.872340 (-6875 4150);
PAINT AQUA (-6875 4150);
DISPLAY INVISIBLE (-6875 4150);
FORCEPROP 2 LAST CDS_LIB mstr_symbols
J 0
(-6950 4150);
PAINT MONO (-6950 4150);
DISPLAY INVISIBLE (-6950 4150);
FORCEPROP 2 LAST BOM_COST PVPP_KLM_VR
J 0
(-7800 4225);
DISPLAY 1.042553 (-7800 4225);
PAINT WHITE (-7800 4225);
DISPLAY INVISIBLE (-7800 4225);
FORCEPROP 2 LAST ROOM PVPP_KLM_VR
J 0
(-7525 4225);
DISPLAY 1.042553 (-7525 4225);
PAINT GREEN (-7525 4225);
DISPLAY INVISIBLE (-7525 4225);
FORCEPROP 1 LAST VOLTAGE 0
J 0
(-6950 4150);
PAINT SKYBLUE (-6950 4150);
DISPLAY INVISIBLE (-6950 4150);
FORCEPROP 1 LAST SIZE 1B
J 0
(-6875 4100);
DISPLAY 0.872340 (-6875 4100);
PAINT GREEN (-6875 4100);
DISPLAY INVISIBLE (-6875 4100);
FORCEADD RES..1
(-3800 4450);
FORCEPROP 1 LAST PACK_TYPE 0603
J 0
(-3925 4300);
DISPLAY 0.617021 (-3925 4300);
PAINT SKYBLUE (-3925 4300);
FORCEPROP 1 LAST VALUE 0
J 0
(-3925 4350);
DISPLAY 0.617021 (-3925 4350);
PAINT SKYBLUE (-3925 4350);
FORCEPROP 1 LASTPIN (-3700 4450) $PN 2
J 0
(-3738 4462);
DISPLAY 0.787234 (-3738 4462);
PAINT ORANGE (-3738 4462);
FORCEPROP 1 LASTPIN (-3900 4450) $PN 1
J 0
(-3888 4462);
DISPLAY 0.787234 (-3888 4462);
PAINT ORANGE (-3888 4462);
FORCEPROP 1 LAST LOCATION R7F8
J 0
(-3900 4500);
DISPLAY 0.617021 (-3900 4500);
PAINT AQUA (-3900 4500);
FORCEPROP 1 LAST MATERIAL CHIP
J 0
(-3625 4375);
DISPLAY 0.617021 (-3625 4375);
PAINT SKYBLUE (-3625 4375);
FORCEPROP 1 LAST PART_NUMBER G22178-002
J 0
(-3925 4400);
DISPLAY 0.617021 (-3925 4400);
PAINT BLUE (-3925 4400);
FORCEPROP 1 LAST TOLERANCE 5.0%
J 0
(-3850 4350);
DISPLAY 0.617021 (-3850 4350);
PAINT SKYBLUE (-3850 4350);
FORCEPROP 1 LAST WATTAGE 1/10W
J 0
(-3800 4300);
DISPLAY 0.617021 (-3800 4300);
PAINT SKYBLUE (-3800 4300);
FORCEPROP 0 LAST CDS_LOCATION R7F8
J 0
(-3725 4450);
PAINT MONO (-3725 4450);
DISPLAY INVISIBLE (-3725 4450);
FORCEPROP 1 LAST PATH I229
J 0
(-3850 4600);
DISPLAY 0.978723 (-3850 4600);
PAINT WHITE (-3850 4600);
DISPLAY INVISIBLE (-3850 4600);
FORCEPROP 0 LAST ROOM NIC_SPRV
J 0
(-3700 4575);
DISPLAY 1.021277 (-3700 4575);
PAINT ORANGE (-3700 4575);
DISPLAY INVISIBLE (-3700 4575);
FORCEPROP 0 LAST BOM_COST NT_GBE_BASE
J 0
(-3700 4675);
DISPLAY 1.021277 (-3700 4675);
PAINT ORANGE (-3700 4675);
DISPLAY INVISIBLE (-3700 4675);
FORCEPROP 2 LAST CDS_LIB mstr_discrete
J 0
(-3800 4450);
PAINT MONO (-3800 4450);
DISPLAY INVISIBLE (-3800 4450);
FORCEPROP 2 LAST SEC_TYPE 0603
J 0
(-3850 4650);
DISPLAY 1.021277 (-3850 4650);
PAINT ORANGE (-3850 4650);
DISPLAY INVISIBLE (-3850 4650);
FORCEPROP 0 LAST SEC 1
J 0
(-4050 4550);
DISPLAY 0.680851 (-4050 4550);
PAINT MONO (-4050 4550);
DISPLAY INVISIBLE (-4050 4550);
FORCEPROP 0 LAST CDS_SEC 1
J 0
(-3725 4450);
PAINT MONO (-3725 4450);
DISPLAY INVISIBLE (-3725 4450);
FORCEADD RES..2
(-1000 1550);
FORCEPROP 1 LAST PACK_TYPE 0402
J 0
(-960 1375);
DISPLAY 0.617021 (-960 1375);
PAINT SKYBLUE (-960 1375);
FORCEPROP 1 LAST PART_NUMBER G21796-161
J 0
(-960 1425);
DISPLAY 0.617021 (-960 1425);
PAINT BLUE (-960 1425);
FORCEPROP 1 LAST MATERIAL CHIP
J 0
(-960 1475);
DISPLAY 0.617021 (-960 1475);
PAINT SKYBLUE (-960 1475);
FORCEPROP 1 LAST WATTAGE 1/16W
J 0
(-960 1525);
DISPLAY 0.617021 (-960 1525);
PAINT SKYBLUE (-960 1525);
FORCEPROP 1 LAST TOLERANCE 1%
J 0
(-955 1575);
DISPLAY 0.617021 (-955 1575);
PAINT SKYBLUE (-955 1575);
FORCEPROP 1 LAST VALUE 6.19K
J 0
(-955 1625);
DISPLAY 0.617021 (-955 1625);
PAINT SKYBLUE (-955 1625);
FORCEPROP 1 LASTPIN (-1000 1650) $PN 1
J 0
(-995 1612);
DISPLAY 0.617021 (-995 1612);
PAINT ORANGE (-995 1612);
FORCEPROP 1 LASTPIN (-1000 1450) $PN 2
J 0
(-995 1460);
DISPLAY 0.617021 (-995 1460);
PAINT ORANGE (-995 1460);
FORCEPROP 1 LAST LOCATION R7F11
J 0
(-955 1675);
DISPLAY 0.617021 (-955 1675);
PAINT AQUA (-955 1675);
FORCEPROP 0 LAST BOM_COST IO_SLOT
J 0
(-950 1875);
DISPLAY 1.021277 (-950 1875);
PAINT ORANGE (-950 1875);
DISPLAY INVISIBLE (-950 1875);
FORCEPROP 2 LAST SEC 1
J 0
(-950 1775);
DISPLAY 0.680851 (-950 1775);
PAINT MONO (-950 1775);
DISPLAY INVISIBLE (-950 1775);
FORCEPROP 2 LAST SEC_TYPE 0402
J 0
(-950 1775);
DISPLAY 1.021277 (-950 1775);
PAINT ORANGE (-950 1775);
DISPLAY INVISIBLE (-950 1775);
FORCEPROP 0 LAST ROOM IO_SLOT
J 0
(-950 1775);
DISPLAY 1.021277 (-950 1775);
PAINT ORANGE (-950 1775);
DISPLAY INVISIBLE (-950 1775);
FORCEPROP 2 LAST CDS_LIB mstr_discrete
J 0
(-1000 1550);
PAINT ORANGE (-1000 1550);
DISPLAY INVISIBLE (-1000 1550);
FORCEPROP 0 LAST CDS_SEC 1
J 0
(-950 1725);
PAINT MONO (-950 1725);
DISPLAY INVISIBLE (-950 1725);
FORCEPROP 1 LAST PATH I230
J 0
(-950 1725);
DISPLAY 0.978723 (-950 1725);
PAINT WHITE (-950 1725);
DISPLAY INVISIBLE (-950 1725);
FORCEPROP 2 LAST CDS_LOCATION R7F11
J 0
(-955 1675);
DISPLAY 0.617021 (-955 1675);
PAINT AQUA (-955 1675);
DISPLAY INVISIBLE (-955 1675);
FORCEADD INTEL_CORP_BPAGE..1
(-125 50);
FORCEPROP 1 LAST CDS_CON_LAST_MODIFIED Fri Jun 16 17:49:23 2017
J 0
(-1550 375);
DISPLAY 0.659574 (-1550 375);
PAINT GREEN (-1550 375);
DISPLAY INVISIBLE (-1550 375);
FORCEPROP 1 LAST CUSTOM_TXT_CDS <CURRENT_DESIGN_SHEET> OF <TOTAL_DESIGN_SHEETS>
J 0
(-625 75);
PAINT ORANGE (-625 75);
FORCEPROP 2 LAST CUSTOM_TXT_CDS <XR_PAGE_TITLE>
J 0
(-8015 5300);
DISPLAY 0.638298 (-8015 5300);
PAINT PINK (-8015 5300);
DISPLAY INVISIBLE (-8015 5300);
FORCEPROP 2 LAST CUSTOM_TXT_CDS <CON_LAST_MODIFIED>
J 0
(-4125 150);
DISPLAY 0.957447 (-4125 150);
PAINT ORANGE (-4125 150);
FORCEPROP 1 LAST SCH_TITLE VPP ABC VR
J 0
(-8075 100);
DISPLAY 1.212766 (-8075 100);
PAINT GREEN (-8075 100);
FORCEPROP 1 LAST COMMENT_BODY TRUE
J 0
(-113 62);
DISPLAY 0.319149 (-113 62);
PAINT GREEN (-113 62);
DISPLAY INVISIBLE (-113 62);
FORCEPROP 2 LAST CDS_LIB mstr_symbols
J 0
(-125 50);
DISPLAY 0.489362 (-125 50);
PAINT ORANGE (-125 50);
DISPLAY INVISIBLE (-125 50);
FORCEPROP 2 LAST PAGE_BORDER TRUE
J 0
(-8015 5300);
DISPLAY 0.425532 (-8015 5300);
PAINT PINK (-8015 5300);
DISPLAY INVISIBLE (-8015 5300);
FORCEPROP 2 LAST CDS_XR_PAGE_TITLE CR-231 : @BASEBOARD_FAB2_LIB.BASEBOARD_FAB2(SCH_1):PAGE231
J 0
(-8015 5300);
DISPLAY 0.638298 (-8015 5300);
PAINT PINK (-8015 5300);
DISPLAY INVISIBLE (-8015 5300);
FORCEADD DNS..2
(-6170 2645);
PAINT RED (-6170 2645);
FORCEPROP 1 LAST COMMENT_BODY TRUE
R 1
J 0
(-6095 2420);
DISPLAY 0.872340 (-6095 2420);
PAINT GREEN (-6095 2420);
DISPLAY INVISIBLE (-6095 2420);
FORCEPROP 2 LAST CDS_LIB mstr_misc
J 0
(-6170 2645);
PAINT ORANGE (-6170 2645);
DISPLAY INVISIBLE (-6170 2645);
FORCEADD CAD_NOTE..1
(-6125 5075);
FORCEPROP 0 LAST LINE2 AND CLOSE TO IC PINS
J 0
(-6275 4875);
DISPLAY 0.787234 (-6275 4875);
PAINT WHITE (-6275 4875);
FORCEPROP 0 LAST LINE PLACE DECOUPLING SAME SIDE
J 0
(-6350 4825);
DISPLAY 0.787234 (-6350 4825);
PAINT WHITE (-6350 4825);
FORCEPROP 1 LAST COMMENT_BODY TRUE
J 0
(-6100 5175);
PAINT PEACH (-6100 5175);
DISPLAY INVISIBLE (-6100 5175);
FORCEPROP 2 LAST CDS_LIB mstr_symbols
J 0
(-6125 5075);
PAINT MONO (-6125 5075);
DISPLAY INVISIBLE (-6125 5075);
FORCEPROP 2 LAST BOM_COST PVPP_KLM_VR
J 0
(-6275 5050);
DISPLAY 1.042553 (-6275 5050);
PAINT WHITE (-6275 5050);
DISPLAY INVISIBLE (-6275 5050);
FORCEPROP 2 LAST ROOM PVPP_KLM_VR
J 0
(-6275 5000);
DISPLAY 1.042553 (-6275 5000);
PAINT GREEN (-6275 5000);
DISPLAY INVISIBLE (-6275 5000);
FORCEADD DNS..2
(-2295 3945);
PAINT RED (-2295 3945);
FORCEPROP 1 LAST COMMENT_BODY TRUE
R 1
J 0
(-2220 3720);
DISPLAY 0.872340 (-2220 3720);
PAINT GREEN (-2220 3720);
DISPLAY INVISIBLE (-2220 3720);
FORCEPROP 2 LAST CDS_LIB mstr_misc
J 0
(-2295 3945);
PAINT ORANGE (-2295 3945);
DISPLAY INVISIBLE (-2295 3945);
FORCEADD DNS..2
(-2295 3595);
PAINT RED (-2295 3595);
FORCEPROP 1 LAST COMMENT_BODY TRUE
R 1
J 0
(-2220 3370);
DISPLAY 0.872340 (-2220 3370);
PAINT GREEN (-2220 3370);
DISPLAY INVISIBLE (-2220 3370);
FORCEPROP 2 LAST CDS_LIB mstr_misc
J 0
(-2295 3595);
PAINT ORANGE (-2295 3595);
DISPLAY INVISIBLE (-2295 3595);
WIRE 16 -1 (-7925 1175)(-7925 1200);
WIRE 16 -1 (-7625 1175)(-7925 1175);
WIRE 16 -1 (-7925 1175)(-7925 1100);
WIRE 16 -1 (-7625 1175)(-7350 1175);
WIRE 16 -1 (-7625 1100)(-7625 1175);
WIRE 16 -1 (-7075 1175)(-7350 1175);
WIRE 16 -1 (-7350 1100)(-7350 1175);
WIRE 16 -1 (-6800 1175)(-7075 1175);
WIRE 16 -1 (-7075 1075)(-7075 1175);
WIRE 16 -1 (-6500 1175)(-6800 1175);
WIRE 16 -1 (-6800 1100)(-6800 1175);
WIRE 16 -1 (-6225 1175)(-6500 1175);
WIRE 16 -1 (-6500 1100)(-6500 1175);
WIRE 16 -1 (-5925 1175)(-6225 1175);
WIRE 16 -1 (-6225 1175)(-6225 1100);
WIRE 16 -1 (-5625 1175)(-5925 1175);
WIRE 16 -1 (-5925 1100)(-5925 1175);
WIRE 16 -1 (-5350 1175)(-5625 1175);
WIRE 16 -1 (-5625 1100)(-5625 1175);
WIRE 16 -1 (-5075 1175)(-5350 1175);
WIRE 16 -1 (-5350 1075)(-5350 1175);
WIRE 16 -1 (-4800 1175)(-5075 1175);
WIRE 16 -1 (-5075 1075)(-5075 1175);
WIRE 16 -1 (-4800 1075)(-4800 1175);
WIRE 16 -1 (-6625 2250)(-6625 2350);
WIRE 16 -1 (-6175 2375)(-6175 2550);
WIRE 16 -1 (-3700 950)(-3700 825);
WIRE 16 -1 (-7925 650)(-7925 625);
WIRE 16 -1 (-7925 650)(-7625 650);
WIRE 16 -1 (-7925 900)(-7925 650);
WIRE 16 -1 (-7625 650)(-7350 650);
WIRE 16 -1 (-7625 900)(-7625 650);
WIRE 16 -1 (-7350 650)(-7075 650);
WIRE 16 -1 (-7350 900)(-7350 650);
WIRE 16 -1 (-7075 650)(-6800 650);
WIRE 16 -1 (-7075 875)(-7075 650);
WIRE 16 -1 (-6800 650)(-6500 650);
WIRE 16 -1 (-6800 900)(-6800 650);
WIRE 16 -1 (-6500 650)(-6225 650);
WIRE 16 -1 (-6500 900)(-6500 650);
WIRE 16 -1 (-6225 650)(-5925 650);
WIRE 16 -1 (-6225 900)(-6225 650);
WIRE 16 -1 (-5925 650)(-5625 650);
WIRE 16 -1 (-5925 900)(-5925 650);
WIRE 16 -1 (-5625 650)(-5350 650);
WIRE 16 -1 (-5625 900)(-5625 650);
WIRE 16 -1 (-5350 650)(-5075 650);
WIRE 16 -1 (-5350 875)(-5350 650);
WIRE 16 -1 (-4800 650)(-5075 650);
WIRE 16 -1 (-5075 875)(-5075 650);
WIRE 16 -1 (-4800 875)(-4800 650);
WIRE 16 -1 (-4700 4200)(-4700 4300);
WIRE 16 -1 (-7500 4600)(-7500 4550);
WIRE 16 -1 (-7500 4550)(-7400 4550);
WIRE 16 -1 (-1000 1300)(-1000 1450);
WIRE 16 -1 (-1250 675)(-1250 725);
WIRE 16 -1 (-1250 725)(-1050 725);
WIRE 16 -1 (-700 675)(-700 725);
WIRE 16 -1 (-700 725)(-850 725);
WIRE 16 -1 (-2300 3500)(-2300 3450);
WIRE 16 -1 (-1725 3725)(-1725 3825);
WIRE 16 -1 (-1400 3575)(-1400 3600);
WIRE 16 -1 (-1100 3600)(-1400 3600);
WIRE 16 -1 (-1400 3600)(-1400 3800);
WIRE 16 -1 (-1100 3800)(-1100 3600);
WIRE 16 -1 (-775 3575)(-775 3800);
WIRE 16 -1 (-475 3825)(-475 3575);
WIRE 16 -1 (-400 4150)(-400 4100);
WIRE 16 -1 (-400 4100)(-475 4100);
WIRE 16 -1 (-175 4100)(-400 4100);
WIRE 16 -1 (-175 4100)(-175 3425);
WIRE 16 -1 (-775 4100)(-475 4100);
WIRE 16 -1 (-475 4100)(-475 4025);
WIRE 16 -1 (-775 4100)(-1100 4100);
WIRE 16 -1 (-775 4100)(-775 4000);
WIRE 16 -1 (-1000 3425)(-175 3425);
WIRE 16 -1 (-1000 3425)(-1000 3275);
WIRE 16 -1 (-1400 4100)(-1100 4100);
WIRE 16 -1 (-1100 4000)(-1100 4100);
WIRE 16 -1 (-1725 4100)(-1400 4100);
WIRE 16 -1 (-1400 4100)(-1400 4000);
WIRE 16 -1 (-1850 4100)(-1725 4100);
WIRE 16 -1 (-1725 4025)(-1725 4100);
WIRE 16 -1 (-4025 2150)(-4025 2275);
WIRE 16 -1 (-4025 2275)(-3950 2275);
WIRE 16 -1 (-4400 1800)(-4400 1650);
WIRE 16 -1 (-3875 1725)(-3875 1600);
WIRE 16 -1 (-4725 2325)(-4725 2250);
WIRE 16 -1 (-2725 2275)(-2725 2225);
WIRE 16 -1 (-2725 2325)(-2725 2275);
WIRE 16 -1 (-2950 2275)(-2725 2275);
WIRE 16 -1 (-2725 2375)(-2725 2325);
WIRE 16 -1 (-2950 2325)(-2725 2325);
WIRE 16 -1 (-2725 2425)(-2725 2375);
WIRE 16 -1 (-2950 2375)(-2725 2375);
WIRE 16 -1 (-2725 2475)(-2725 2425);
WIRE 16 -1 (-2950 2425)(-2725 2425);
WIRE 16 -1 (-2725 2525)(-2725 2475);
WIRE 16 -1 (-2950 2475)(-2725 2475);
WIRE 16 -1 (-2725 2575)(-2725 2525);
WIRE 16 -1 (-2950 2525)(-2725 2525);
WIRE 16 -1 (-2725 2625)(-2725 2575);
WIRE 16 -1 (-2950 2575)(-2725 2575);
WIRE 16 -1 (-2725 2675)(-2725 2625);
WIRE 16 -1 (-2950 2625)(-2725 2625);
WIRE 16 -1 (-2725 2725)(-2725 2675);
WIRE 16 -1 (-2950 2675)(-2725 2675);
WIRE 16 -1 (-2725 2775)(-2725 2725);
WIRE 16 -1 (-2950 2725)(-2725 2725);
WIRE 16 -1 (-2725 2825)(-2725 2775);
WIRE 16 -1 (-2950 2775)(-2725 2775);
WIRE 16 -1 (-2725 2875)(-2725 2825);
WIRE 16 -1 (-2950 2825)(-2725 2825);
WIRE 16 -1 (-2725 2925)(-2725 2875);
WIRE 16 -1 (-2950 2875)(-2725 2875);
WIRE 16 -1 (-2725 2975)(-2725 2925);
WIRE 16 -1 (-2950 2925)(-2725 2925);
WIRE 16 -1 (-2950 2975)(-2725 2975);
WIRE 16 -1 (-5375 2375)(-5375 2525);
WIRE 16 -1 (-5025 3175)(-5025 3000);
WIRE 16 -1 (-3950 3175)(-5025 3175);
WIRE 16 -1 (-4775 3650)(-4775 3575);
WIRE 16 -1 (-5425 4275)(-5425 4225);
WIRE 16 -1 (-5825 4275)(-5825 4225);
WIRE 16 -1 (-6225 4275)(-6225 4225);
WIRE 16 -1 (-5075 4275)(-5075 4225);
WIRE 16 -1 (-6650 4250)(-6650 4200);
WIRE 16 -1 (-6950 4250)(-6950 4200);
WIRE 68 -1 (-7050 4100)(-7050 4650);
WIRE 68 -1 (-7050 4650)(-6375 4650);
WIRE 68 -1 (-7050 4100)(-6375 4100);
WIRE 68 -1 (-6375 4100)(-6375 4650);
WIRE 16 -1 (-3950 3375)(-4375 3375);
WIRE 16 -1 (-4375 3375)(-4375 3425);
WIRE 16 -1 (-3950 3425)(-4375 3425);
WIRE 16 -1 (-4375 3425)(-4375 3475);
WIRE 16 -1 (-3950 3475)(-4375 3475);
WIRE 16 -1 (-4375 3475)(-4375 3525);
WIRE 16 -1 (-3950 3525)(-4375 3525);
WIRE 16 -1 (-4375 3525)(-4375 3575);
WIRE 16 -1 (-3950 3575)(-4375 3575);
WIRE 16 -1 (-4375 3575)(-4375 3625);
WIRE 16 -1 (-3950 3625)(-4375 3625);
WIRE 16 -1 (-4375 3625)(-4375 3675);
WIRE 16 -1 (-3950 3675)(-4375 3675);
WIRE 16 -1 (-4375 3675)(-4375 3725);
WIRE 16 -1 (-4375 3725)(-3950 3725);
WIRE 16 -1 (-4375 3825)(-4375 3725);
WIRE 16 -1 (-3950 3825)(-4375 3825);
WIRE 16 -1 (-4775 3850)(-4775 3950);
WIRE 16 -1 (-4775 3950)(-4375 3950);
WIRE 16 -1 (-4375 3950)(-4375 3825);
WIRE 16 -1 (-7200 4550)(-6950 4550);
WIRE 16 -1 (-6950 4400)(-6950 4550);
WIRE 16 -1 (-4375 4550)(-4375 3950);
WIRE 16 -1 (-4700 4500)(-4700 4550);
WIRE 16 -1 (-4375 4550)(-4700 4550);
WIRE 16 -1 (-6950 4550)(-6650 4550);
WIRE 16 -1 (-6650 4550)(-6650 4400);
WIRE 16 -1 (-6225 4550)(-6650 4550);
WIRE 16 -1 (-6225 4475)(-6225 4550);
WIRE 16 -1 (-5075 4475)(-5075 4550);
WIRE 16 -1 (-4700 4550)(-5075 4550);
WIRE 16 -1 (-5425 4475)(-5425 4550);
WIRE 16 -1 (-5075 4550)(-5425 4550);
WIRE 16 -1 (-5825 4550)(-6225 4550);
WIRE 16 -1 (-5825 4475)(-5825 4550);
WIRE 16 -1 (-5825 4550)(-5425 4550);
FORCEPROP 0 LAST SIG_NAME VR_FET_SW_P12V_STBY_PVPP_ABC
J 0
(-5560 4560);
DISPLAY 0.617021 (-5560 4560);
PAINT ORANGE (-5560 4560);
FORCEPROP 2 LASTPROP $XRERR UNIQUE?
J 0
(-5800 4560);
DISPLAY 0.638298 (-5800 4560);
PAINT MONO (-5800 4560);
DISPLAY INVISIBLE (-5800 4560);
WIRE 16 -1 (-5675 3075)(-3950 3075);
FORCEPROP 2 LAST SIG_NAME FM_PVPP_PVDDQ_CPU0_EN_ABC
J 0
(-4926 3100);
DISPLAY 0.617021 (-4926 3100);
PAINT ORANGE (-4926 3100);
FORCEPROP 2 LASTPROP $XRERR UNIQUE?
J 0
(-5166 3100);
DISPLAY 0.638298 (-5166 3100);
PAINT MONO (-5166 3100);
DISPLAY INVISIBLE (-5166 3100);
WIRE 16 2175 (-4050 4250)(-4050 4625);
WIRE 16 2175 (-2825 4250)(-4050 4250);
WIRE 16 2175 (-4050 4625)(-2825 4625);
WIRE 16 2175 (-2825 4625)(-2825 4250);
WIRE 16 -1 (-8075 450)(-8075 1425);
WIRE 16 2175 (-4475 450)(-8075 450);
WIRE 16 2175 (-8075 1425)(-4475 1425);
WIRE 16 2175 (-4475 1425)(-4475 450);
WIRE 3 682 (-5050 2775)(-5650 2775);
WIRE 3 682 (-5050 2300)(-5050 2775);
WIRE 3 682 (-5650 2775)(-5650 2300);
WIRE 3 682 (-5650 2300)(-5050 2300);
WIRE 16 2175 (-4775 4050)(-7100 4050);
WIRE 16 2175 (-4775 4600)(-4775 4050);
WIRE 16 2175 (-7100 4050)(-7100 4600);
WIRE 16 2175 (-7100 4600)(-4775 4600);
WIRE 16 -1 (-675 1900)(-675 1850);
WIRE 16 -1 (-675 1850)(-1000 1850);
WIRE 16 -1 (-1000 2150)(-1000 1850);
WIRE 16 -1 (-1000 1800)(-1000 1650);
WIRE 16 -1 (-1000 1850)(-1000 1800);
WIRE 16 -1 (-1525 1800)(-1000 1800);
FORCEPROP 0 LAST SIG_NAME VR_FB_PVPP_ABC
J 0
(-1485 1810);
DISPLAY 0.617021 (-1485 1810);
PAINT ORANGE (-1485 1810);
FORCEPROP 2 LASTPROP $XRERR UNIQUE?
J 0
(-1725 1810);
DISPLAY 0.638298 (-1725 1810);
PAINT MONO (-1725 1810);
DISPLAY INVISIBLE (-1725 1810);
WIRE 16 -1 (-1525 1800)(-1525 3175);
WIRE 16 -1 (-2950 3175)(-1625 3175);
WIRE 16 -1 (-1525 3175)(-1625 3175);
WIRE 16 -1 (-1775 3075)(-1625 3075);
WIRE 16 -1 (-1625 3075)(-1625 3175);
WIRE 16 -1 (-1625 2700)(-1700 2700);
WIRE 16 -1 (-1625 2700)(-1625 3075);
WIRE 16 -1 (-1900 2700)(-2400 2700);
FORCEPROP 0 LAST SIG_NAME VR_COMP_RC_PVPP_ABC
J 0
(-2385 2710);
DISPLAY 0.617021 (-2385 2710);
PAINT ORANGE (-2385 2710);
FORCEPROP 2 LASTPROP $XRERR UNIQUE?
J 0
(-2625 2710);
DISPLAY 0.638298 (-2625 2710);
PAINT MONO (-2625 2710);
DISPLAY INVISIBLE (-2625 2710);
WIRE 16 -1 (-2950 3075)(-2650 3075);
WIRE 16 -1 (-2650 3075)(-1975 3075);
WIRE 16 -1 (-2650 2700)(-2650 3075);
FORCEPROP 0 LAST SIG_NAME VR_COMP_PVPP_ABC_3
J 0
(-2610 3085);
DISPLAY 0.617021 (-2610 3085);
PAINT ORANGE (-2610 3085);
FORCEPROP 2 LASTPROP $XRERR UNIQUE?
J 0
(-2850 3085);
DISPLAY 0.638298 (-2850 3085);
PAINT MONO (-2850 3085);
DISPLAY INVISIBLE (-2850 3085);
WIRE 16 -1 (-2600 2700)(-2650 2700);
WIRE 16 -1 (-6175 2750)(-6175 3075);
WIRE 16 -1 (-6175 3075)(-5875 3075);
WIRE 16 -1 (-6625 2550)(-6625 3075);
WIRE 16 -1 (-6625 3075)(-6175 3075);
WIRE 16 -1 (-7000 3075)(-6625 3075);
FORCEPROP 2 LAST SIG_NAME FM_PVPP_CPU0_EN
J 0
(-6901 3100);
DISPLAY 0.617021 (-6901 3100);
PAINT ORANGE (-6901 3100);
WIRE 16 -1 (-675 2100)(-675 2700);
FORCEPROP 0 LAST SIG_NAME VR_COMP_PVPP_ABC
R 1
J 0
(-685 2160);
DISPLAY 0.617021 (-685 2160);
PAINT ORANGE (-685 2160);
FORCEPROP 2 LASTPROP $XRERR UNIQUE?
J 0
(-925 2160);
DISPLAY 0.638298 (-925 2160);
PAINT MONO (-925 2160);
DISPLAY INVISIBLE (-925 2160);
WIRE 16 -1 (-2450 1225)(-2900 1225);
FORCEPROP 2 LAST SIG_NAME PWRGD_PVPP_ABC
J 0
(-2835 1235);
DISPLAY 0.617021 (-2835 1235);
PAINT ORANGE (-2835 1235);
WIRE 16 -1 (-3125 4450)(-3700 4450);
FORCEPROP 2 LAST SIG_NAME VR_PVPP_ABC_BOOT_R
J 0
(-3655 4460);
DISPLAY 0.617021 (-3655 4460);
PAINT ORANGE (-3655 4460);
FORCEPROP 2 LASTPROP $XRERR UNIQUE?
J 0
(-3895 4460);
DISPLAY 0.638298 (-3895 4460);
PAINT MONO (-3895 4460);
DISPLAY INVISIBLE (-3895 4460);
WIRE 16 682 (-1675 4875)(-1675 4375);
WIRE 16 682 (-275 4875)(-1675 4875);
WIRE 16 682 (-1675 4375)(-275 4375);
WIRE 16 682 (-275 4375)(-275 4875);
WIRE 16 -1 (-2300 3700)(-2300 3850);
FORCEPROP 2 LAST SIG_NAME VR_PVPP_ABC_SNUB
J 0
(-2285 3760);
DISPLAY 0.617021 (-2285 3760);
PAINT ORANGE (-2285 3760);
FORCEPROP 2 LASTPROP $XRERR UNIQUE?
J 0
(-2525 3760);
DISPLAY 0.638298 (-2525 3760);
PAINT MONO (-2525 3760);
DISPLAY INVISIBLE (-2525 3760);
WIRE 16 -1 (-2950 3275)(-2675 3275);
WIRE 16 -1 (-2950 3375)(-2675 3375);
WIRE 16 -1 (-2675 3275)(-2675 3375);
WIRE 16 -1 (-2950 3425)(-2675 3425);
WIRE 16 -1 (-2675 3375)(-2675 3425);
WIRE 16 -1 (-2950 3475)(-2675 3475);
WIRE 16 -1 (-2675 3425)(-2675 3475);
WIRE 16 -1 (-2950 3525)(-2675 3525);
WIRE 16 -1 (-2675 3475)(-2675 3525);
WIRE 16 -1 (-2950 3575)(-2675 3575);
WIRE 16 -1 (-2675 3525)(-2675 3575);
WIRE 16 -1 (-2675 3575)(-2675 3625);
WIRE 16 -1 (-2950 3625)(-2675 3625);
WIRE 16 -1 (-2950 3675)(-2675 3675);
WIRE 16 -1 (-2675 3625)(-2675 3675);
WIRE 16 -1 (-2925 4450)(-2675 4450);
WIRE 16 -1 (-2950 3725)(-2675 3725);
WIRE 16 -1 (-2675 3675)(-2675 3725);
WIRE 16 -1 (-2675 3725)(-2675 4100);
WIRE 16 -1 (-2675 4450)(-2675 4100);
WIRE 16 -1 (-2300 4050)(-2300 4100);
WIRE 16 -1 (-2675 4100)(-2300 4100);
FORCEPROP 2 LAST SIG_NAME VR_PVPP_ABC_PHASE
J 0
(-2660 4110);
DISPLAY 0.617021 (-2660 4110);
PAINT ORANGE (-2660 4110);
FORCEPROP 2 LASTPROP $XRERR UNIQUE?
J 0
(-2900 4110);
DISPLAY 0.638298 (-2900 4110);
PAINT MONO (-2900 4110);
DISPLAY INVISIBLE (-2900 4110);
WIRE 16 -1 (-2050 4100)(-2300 4100);
WIRE 16 -1 (-2900 3825)(-2950 3825);
WIRE 16 -1 (-2900 4150)(-2900 3825);
WIRE 16 -1 (-3950 4150)(-2900 4150);
WIRE 16 -1 (-3950 4450)(-3950 4150);
FORCEPROP 2 LAST SIG_NAME VR_PVPP_ABC_BOOT
J 0
(-3860 4185);
DISPLAY 0.617021 (-3860 4185);
PAINT ORANGE (-3860 4185);
FORCEPROP 2 LASTPROP $XRERR UNIQUE?
J 0
(-4100 4185);
DISPLAY 0.638298 (-4100 4185);
PAINT MONO (-4100 4185);
DISPLAY INVISIBLE (-4100 4185);
WIRE 16 -1 (-3900 4450)(-3950 4450);
WIRE 3 682 (-4000 4550)(-4000 4275);
WIRE 3 682 (-3675 4550)(-4000 4550);
WIRE 3 682 (-4000 4275)(-3675 4275);
WIRE 3 682 (-3675 4275)(-3675 4550);
WIRE 16 -1 (-4725 2975)(-4725 2525);
FORCEPROP 2 LAST SIG_NAME VR_PVPP_ABC_SS
R 1
J 0
(-4735 2535);
DISPLAY 0.617021 (-4735 2535);
PAINT ORANGE (-4735 2535);
FORCEPROP 2 LASTPROP $XRERR UNIQUE?
J 0
(-4975 2535);
DISPLAY 0.638298 (-4975 2535);
PAINT MONO (-4975 2535);
DISPLAY INVISIBLE (-4975 2535);
WIRE 16 -1 (-3950 2975)(-4725 2975);
WIRE 16 -1 (-5375 2725)(-5375 3275);
WIRE 16 -1 (-5375 3275)(-3950 3275);
FORCEPROP 0 LAST SIG_NAME VR_VB_PVPP_ABC
J 0
(-5085 3285);
DISPLAY 0.617021 (-5085 3285);
PAINT ORANGE (-5085 3285);
FORCEPROP 2 LASTPROP $XRERR UNIQUE?
J 0
(-5325 3285);
DISPLAY 0.638298 (-5325 3285);
PAINT MONO (-5325 3285);
DISPLAY INVISIBLE (-5325 3285);
WIRE 16 -1 (-3950 2775)(-4200 2775);
WIRE 16 -1 (-4200 1225)(-4200 2775);
WIRE 16 -1 (-3875 1225)(-4200 1225);
WIRE 16 -1 (-3875 1400)(-3875 1225);
WIRE 16 -1 (-3700 1225)(-3875 1225);
WIRE 16 -1 (-3700 1150)(-3700 1225);
WIRE 16 -1 (-3100 1225)(-3700 1225);
FORCEPROP 2 LAST SIG_NAME PWRGD_PVPP_ABC_R
J 0
(-3610 1235);
DISPLAY 0.617021 (-3610 1235);
PAINT ORANGE (-3610 1235);
FORCEPROP 2 LASTPROP $XRERR UNIQUE?
J 0
(-3850 1235);
DISPLAY 0.638298 (-3850 1235);
PAINT MONO (-3850 1235);
DISPLAY INVISIBLE (-3850 1235);
WIRE 3 682 (-4950 1500)(-4250 1500);
WIRE 3 682 (-4950 2100)(-4950 1500);
WIRE 3 682 (-4250 1500)(-4250 2100);
WIRE 3 682 (-4250 2100)(-4950 2100);
WIRE 16 -1 (-4400 2000)(-4400 2875);
FORCEPROP 2 LAST SIG_NAME VR_PVPP_ABC_ISET
R 1
J 0
(-4410 2360);
DISPLAY 0.617021 (-4410 2360);
PAINT ORANGE (-4410 2360);
FORCEPROP 2 LASTPROP $XRERR UNIQUE?
J 0
(-4650 2360);
DISPLAY 0.638298 (-4650 2360);
PAINT MONO (-4650 2360);
DISPLAY INVISIBLE (-4650 2360);
WIRE 16 -1 (-4400 2875)(-3950 2875);
WIRE 16 -1 (-675 2900)(-675 2925);
WIRE 16 -1 (-675 2925)(-1000 2925);
WIRE 16 -1 (-1000 3075)(-1000 2925);
WIRE 16 -1 (-1000 2350)(-1000 2925);
FORCEPROP 0 LAST SIG_NAME VSENSE_PVPP_ABC
R 1
J 0
(-1010 2385);
DISPLAY 0.617021 (-1010 2385);
PAINT ORANGE (-1010 2385);
FORCEPROP 2 LASTPROP $XRERR UNIQUE?
J 0
(-1250 2385);
DISPLAY 0.638298 (-1250 2385);
PAINT MONO (-1250 2385);
DISPLAY INVISIBLE (-1250 2385);
WIRE 3 682 (-650 1350)(-1150 1350);
WIRE 3 682 (-650 1750)(-650 1350);
WIRE 3 682 (-1150 1350)(-1150 1750);
WIRE 3 682 (-1150 1750)(-650 1750);
WIRE 16 2175 (-1075 1325)(-325 1325);
WIRE 16 2175 (-325 3375)(-325 1325);
WIRE 16 2175 (-1075 1325)(-1075 3375);
WIRE 16 2175 (-1075 3375)(-325 3375);
DOT 1 (-4375 3675);
DOT 1 (-1400 3600);
DOT 1 (-1100 4100);
DOT 1 (-6950 4550);
DOT 1 (-6650 4550);
DOT 1 (-6225 4550);
DOT 1 (-5825 4550);
DOT 1 (-5425 4550);
DOT 1 (-7075 1175);
DOT 1 (-6500 1175);
DOT 1 (-6225 1175);
DOT 1 (-6625 3075);
DOT 1 (-6175 3075);
DOT 1 (-5350 1175);
DOT 1 (-4375 3425);
DOT 1 (-4375 3475);
DOT 1 (-4375 3525);
DOT 1 (-4375 3575);
DOT 1 (-4375 3725);
DOT 1 (-4375 3950);
DOT 1 (-5075 4550);
DOT 1 (-3875 1225);
DOT 1 (-2725 2275);
DOT 1 (-2725 2325);
DOT 1 (-2725 2375);
DOT 1 (-2725 2425);
DOT 1 (-2725 2525);
DOT 1 (-2725 2575);
DOT 1 (-2725 2825);
DOT 1 (-2725 2875);
DOT 1 (-2725 2925);
DOT 1 (-2650 3075);
DOT 1 (-2675 3575);
DOT 1 (-2675 3525);
DOT 1 (-2675 3375);
DOT 1 (-2675 3475);
DOT 1 (-2675 3425);
DOT 1 (-2675 3725);
DOT 1 (-2675 3625);
DOT 1 (-2675 3675);
DOT 1 (-1625 3075);
DOT 1 (-2300 4100);
DOT 1 (-1725 4100);
DOT 1 (-2675 4100);
DOT 1 (-1400 4100);
DOT 1 (-7625 1175);
DOT 1 (-7350 1175);
DOT 1 (-7925 1175);
DOT 1 (-3700 1225);
DOT 1 (-1000 1800);
DOT 1 (-1000 1850);
DOT 1 (-475 4100);
DOT 1 (-775 4100);
DOT 1 (-4700 4550);
DOT 1 (-4375 3825);
DOT 1 (-4375 3625);
DOT 1 (-2725 2475);
DOT 1 (-400 4100);
DOT 1 (-1000 2925);
DOT 1 (-2725 2625);
DOT 1 (-2725 2675);
DOT 1 (-2725 2725);
DOT 1 (-2725 2775);
DOT 1 (-5075 1175);
DOT 1 (-5625 1175);
DOT 1 (-5925 1175);
DOT 1 (-7925 650);
DOT 1 (-7625 650);
DOT 1 (-6225 650);
DOT 1 (-6800 650);
DOT 1 (-7350 650);
DOT 1 (-5925 650);
DOT 1 (-5075 650);
DOT 1 (-5625 650);
DOT 1 (-5350 650);
DOT 1 (-6500 650);
DOT 1 (-7075 650);
DOT 1 (-6800 1175);
DOT 1 (-1625 3175);
FORCENOTE
PUT TOGETHER
(-7025 4650) 0;
DISPLAY LEFT (-7025 4650);
DISPLAY 0.808511 (-7025 4650);
PAINT PURPLE (-7025 4650);
FORCENOTE
SPOF
(-4050 4675) 0;
DISPLAY LEFT (-4050 4675);
DISPLAY 1.659574 (-4050 4675);
PAINT PURPLE (-4050 4675);
FORCENOTE
PLACE ON
(-3750 4675) 0;
DISPLAY LEFT (-3750 4675);
DISPLAY 1.042553 (-3750 4675);
PAINT PURPLE (-3750 4675);
FORCENOTE
TOP LAYER
(-3375 4675) 0;
DISPLAY LEFT (-3375 4675);
DISPLAY 1.042553 (-3375 4675);
PAINT PURPLE (-3375 4675);
FORCENOTE
VOUT = 2.5V
(-1650 4800) 0;
DISPLAY LEFT (-1650 4800);
DISPLAY 1.021277 (-1650 4800);
PAINT PURPLE (-1650 4800);
FORCENOTE
SW FREQ =  500KHZ
(-1650 4400) 0;
DISPLAY LEFT (-1650 4400);
DISPLAY 1.021277 (-1650 4400);
PAINT PURPLE (-1650 4400);
FORCENOTE
6.25MS
(-4995 2480) 0;
DISPLAY LEFT (-4995 2480);
PAINT PURPLE (-4995 2480);
FORCENOTE
DC TOL = +/-1.5%
(-1650 4700) 0;
DISPLAY LEFT (-1650 4700);
DISPLAY 1.021277 (-1650 4700);
PAINT PURPLE (-1650 4700);
FORCENOTE
AC & RIPPLE TOL = +3.5%, -7.3%
(-1650 4650) 0;
DISPLAY LEFT (-1650 4650);
DISPLAY 1.021277 (-1650 4650);
PAINT PURPLE (-1650 4650);
FORCENOTE
RIPPLE GUIDELINE = +/- 1.0%
(-1650 4750) 0;
DISPLAY LEFT (-1650 4750);
DISPLAY 1.021277 (-1650 4750);
PAINT PURPLE (-1650 4750);
FORCENOTE
IOUT PK = 10.1A (INCLUDED CPU PVPP)
(-1650 4550) 0;
DISPLAY LEFT (-1650 4550);
DISPLAY 1.021277 (-1650 4550);
PAINT PURPLE (-1650 4550);
FORCENOTE
IOUT STEP = 5.3A
(-1650 4500) 0;
DISPLAY LEFT (-1650 4500);
DISPLAY 1.021277 (-1650 4500);
PAINT PURPLE (-1650 4500);
FORCENOTE
IOUT DI/DT = 21.5A/US
(-1650 4450) 0;
DISPLAY LEFT (-1650 4450);
DISPLAY 1.021277 (-1650 4450);
PAINT PURPLE (-1650 4450);
FORCENOTE
POINT ONLY TOP TO L2
(-1300 875) 0;
DISPLAY LEFT (-1300 875);
DISPLAY 1.042553 (-1300 875);
PAINT PURPLE (-1300 875);
FORCENOTE
TP FAB1 CHANGE RES 0531
(-2075 1350) 0;
DISPLAY LEFT (-2075 1350);
DISPLAY 1.021277 (-2075 1350);
PAINT RED (-2075 1350);
FORCENOTE
(0.4V/MS)
(-5045 2430) 0;
DISPLAY LEFT (-5045 2430);
PAINT PURPLE (-5045 2430);
FORCENOTE
TP FAB1 CHANGE CAP 0422
(-5750 2200) 0;
DISPLAY LEFT (-5750 2200);
DISPLAY 1.021277 (-5750 2200);
PAINT RED (-5750 2200);
FORCENOTE
TP FAB3 CHANGE RES 0822
(-4950 1450) 0;
DISPLAY LEFT (-4950 1450);
DISPLAY 0.638298 (-4950 1450);
PAINT RED (-4950 1450);
FORCENOTE
12A OC
(-4845 1855) 0;
DISPLAY LEFT (-4845 1855);
PAINT PURPLE (-4845 1855);
FORCENOTE
CAPS TO BE PLACED BETWEEN DIMMS
(-7495 1330) 0;
DISPLAY LEFT (-7495 1330);
DISPLAY 1.021277 (-7495 1330);
PAINT PURPLE (-7495 1330);
FORCENOTE
BOM_COST: PVPP_ABC_VR
(-7225 150) 0;
DISPLAY LEFT (-7225 150);
DISPLAY 0.787234 (-7225 150);
PAINT PURPLE (-7225 150);
FORCENOTE
ROOM = PVPP_ABC_VR
(-7225 200) 0;
DISPLAY LEFT (-7225 200);
DISPLAY 0.787234 (-7225 200);
PAINT PURPLE (-7225 200);
FORCENOTE
SPOF
(-855 3225) 0;
DISPLAY LEFT (-855 3225);
DISPLAY 2.340426 (-855 3225);
PAINT PURPLE (-855 3225);
FORCENOTE
CONNECT AT SINGLE
(-1250 925) 0;
DISPLAY LEFT (-1250 925);
DISPLAY 1.042553 (-1250 925);
PAINT PURPLE (-1250 925);
FORCENOTE
IOUT TDC = 7.21A (INCLUDED CPU PVPP)
(-1650 4600) 0;
DISPLAY LEFT (-1650 4600);
DISPLAY 1.021277 (-1650 4600);
PAINT PURPLE (-1650 4600);
FORCENOTE
TP FAB1 CHANGE RES PACKAGE TO 0603
(-4025 4575) 0;
DISPLAY LEFT (-4025 4575);
DISPLAY 0.638298 (-4025 4575);
PAINT RED (-4025 4575);
FORCENOTE
COMPENSATION TYPE III
(-2625 2400) 0;
DISPLAY LEFT (-2625 2400);
DISPLAY 1.042553 (-2625 2400);
PAINT PURPLE (-2625 2400);
FORCENOTE
TP FAB1 CHANGE ONE 47UF CPA TO TWO 22UF CAPS 0107
(-7125 3950) 0;
DISPLAY LEFT (-7125 3950);
DISPLAY 1.021277 (-7125 3950);
PAINT RED (-7125 3950);
QUIT
